(kicad_sch (version 20230121) (generator eeschema)

  (paper "A3")

  (title_block
    (title "HDMI-MIPI Bridge")
    (date "2023-07-20")
    (rev "1.3.1")
  )

  (junction (at 210.82 205.74) (diameter 0) (color 0 0 0 0)
  )
  (junction (at 358.14 205.74) (diameter 0) (color 0 0 0 0)
  )
  (junction (at 336.55 38.1) (diameter 0) (color 0 0 0 0)
  )
  (junction (at 318.77 83.82) (diameter 0) (color 0 0 0 0)
  )
  (junction (at 364.49 38.1) (diameter 0) (color 0 0 0 0)
  )
  (junction (at 316.23 38.1) (diameter 0) (color 0 0 0 0)
  )
  (junction (at 219.71 205.74) (diameter 0) (color 0 0 0 0)
  )
  (junction (at 330.835 38.1) (diameter 0) (color 0 0 0 0)
  )
  (junction (at 210.82 160.02) (diameter 0) (color 0 0 0 0)
  )
  (junction (at 89.535 76.2) (diameter 0) (color 0 0 0 0)
  )
  (junction (at 219.71 220.98) (diameter 0) (color 0 0 0 0)
  )
  (junction (at 219.71 144.78) (diameter 0) (color 0 0 0 0)
  )
  (junction (at 236.22 160.02) (diameter 0) (color 0 0 0 0)
  )
  (junction (at 231.14 220.98) (diameter 0) (color 0 0 0 0)
  )
  (junction (at 327.66 100.33) (diameter 0) (color 0 0 0 0)
  )
  (junction (at 231.14 190.5) (diameter 0) (color 0 0 0 0)
  )
  (junction (at 210.185 144.78) (diameter 0) (color 0 0 0 0)
  )
  (junction (at 125.73 97.79) (diameter 0) (color 0 0 0 0)
  )
  (junction (at 210.82 190.5) (diameter 0) (color 0 0 0 0)
  )
  (junction (at 219.71 238.76) (diameter 0) (color 0 0 0 0)
  )
  (junction (at 330.2 171.45) (diameter 0) (color 0 0 0 0)
  )
  (junction (at 231.14 238.76) (diameter 0) (color 0 0 0 0)
  )
  (junction (at 114.3 84.455) (diameter 0) (color 0 0 0 0)
  )
  (junction (at 360.68 100.33) (diameter 0) (color 0 0 0 0)
  )
  (junction (at 210.82 238.76) (diameter 0) (color 0 0 0 0)
  )
  (junction (at 360.68 83.82) (diameter 0) (color 0 0 0 0)
  )
  (junction (at 182.88 218.44) (diameter 0) (color 0 0 0 0)
  )
  (junction (at 114.3 76.2) (diameter 0) (color 0 0 0 0)
  )
  (junction (at 210.82 220.98) (diameter 0) (color 0 0 0 0)
  )
  (junction (at 307.34 83.82) (diameter 0) (color 0 0 0 0)
  )
  (junction (at 89.535 78.74) (diameter 0) (color 0 0 0 0)
  )
  (junction (at 114.3 45.72) (diameter 0) (color 0 0 0 0)
  )
  (junction (at 369.57 102.87) (diameter 0) (color 0 0 0 0)
  )
  (junction (at 236.22 144.78) (diameter 0) (color 0 0 0 0)
  )
  (junction (at 326.39 38.1) (diameter 0) (color 0 0 0 0)
  )
  (junction (at 330.2 205.74) (diameter 0) (color 0 0 0 0)
  )
  (junction (at 358.14 171.45) (diameter 0) (color 0 0 0 0)
  )
  (junction (at 121.92 97.79) (diameter 0) (color 0 0 0 0)
  )
  (junction (at 114.3 60.96) (diameter 0) (color 0 0 0 0)
  )
  (junction (at 152.4 193.04) (diameter 0) (color 0 0 0 0)
  )
  (junction (at 382.27 38.1) (diameter 0) (color 0 0 0 0)
  )
  (junction (at 219.71 160.02) (diameter 0) (color 0 0 0 0)
  )
  (junction (at 89.535 73.66) (diameter 0) (color 0 0 0 0)
  )
  (junction (at 302.26 38.1) (diameter 0) (color 0 0 0 0)
  )
  (junction (at 195.58 215.9) (diameter 0) (color 0 0 0 0)
  )
  (junction (at 254 220.98) (diameter 0) (color 0 0 0 0)
  )
  (junction (at 210.82 175.26) (diameter 0) (color 0 0 0 0)
  )
  (junction (at 219.71 190.5) (diameter 0) (color 0 0 0 0)
  )
  (junction (at 330.2 208.28) (diameter 0) (color 0 0 0 0)
  )
  (junction (at 146.05 180.34) (diameter 0) (color 0 0 0 0)
  )
  (junction (at 327.66 83.82) (diameter 0) (color 0 0 0 0)
  )
  (junction (at 188.595 218.44) (diameter 0) (color 0 0 0 0)
  )
  (junction (at 114.3 53.34) (diameter 0) (color 0 0 0 0)
  )
  (junction (at 369.57 83.82) (diameter 0) (color 0 0 0 0)
  )
  (junction (at 292.1 38.1) (diameter 0) (color 0 0 0 0)
  )
  (junction (at 330.2 173.99) (diameter 0) (color 0 0 0 0)
  )
  (junction (at 219.71 175.26) (diameter 0) (color 0 0 0 0)
  )
  (junction (at 318.77 102.87) (diameter 0) (color 0 0 0 0)
  )
  (junction (at 89.535 71.12) (diameter 0) (color 0 0 0 0)
  )
  (junction (at 152.4 198.12) (diameter 0) (color 0 0 0 0)
  )
  (junction (at 231.14 205.74) (diameter 0) (color 0 0 0 0)
  )
  (junction (at 254 205.74) (diameter 0) (color 0 0 0 0)
  )
  (junction (at 182.245 185.42) (diameter 0) (color 0 0 0 0)
  )
  (junction (at 381 83.82) (diameter 0) (color 0 0 0 0)
  )

  (no_connect (at 106.68 245.11))
  (no_connect (at 59.69 190.5))
  (no_connect (at 106.68 232.41))
  (no_connect (at 106.68 229.87))
  (no_connect (at 106.68 237.49))
  (no_connect (at 154.94 185.42))
  (no_connect (at 106.68 234.95))

  (wire (pts (xy 182.245 182.88) (xy 182.245 185.42))
    (stroke (width 0) (type default))
  )
  (wire (pts (xy 26.67 63.5) (xy 48.26 63.5))
    (stroke (width 0) (type default))
  )
  (wire (pts (xy 201.93 177.8) (xy 180.34 177.8))
    (stroke (width 0) (type default))
  )
  (wire (pts (xy 332.74 105.41) (xy 332.74 107.315))
    (stroke (width 0) (type default))
  )
  (wire (pts (xy 38.1 160.02) (xy 59.69 160.02))
    (stroke (width 0) (type default))
  )
  (wire (pts (xy 114.3 84.455) (xy 114.3 85.09))
    (stroke (width 0) (type default))
  )
  (wire (pts (xy 205.74 175.26) (xy 205.74 185.42))
    (stroke (width 0) (type default))
  )
  (wire (pts (xy 90.17 193.04) (xy 104.14 193.04))
    (stroke (width 0) (type default))
  )
  (wire (pts (xy 194.945 218.44) (xy 195.58 218.44))
    (stroke (width 0) (type default))
  )
  (wire (pts (xy 97.79 63.5) (xy 116.84 63.5))
    (stroke (width 0) (type default))
  )
  (wire (pts (xy 332.74 105.41) (xy 335.28 105.41))
    (stroke (width 0) (type default))
  )
  (wire (pts (xy 97.79 58.42) (xy 116.84 58.42))
    (stroke (width 0) (type default))
  )
  (wire (pts (xy 205.74 205.74) (xy 210.82 205.74))
    (stroke (width 0) (type default))
  )
  (wire (pts (xy 219.71 182.88) (xy 219.71 185.42))
    (stroke (width 0) (type default))
  )
  (wire (pts (xy 195.58 218.44) (xy 195.58 215.9))
    (stroke (width 0) (type default))
  )
  (wire (pts (xy 119.38 104.14) (xy 121.92 104.14))
    (stroke (width 0) (type default))
  )
  (wire (pts (xy 26.67 55.88) (xy 48.26 55.88))
    (stroke (width 0) (type default))
  )
  (wire (pts (xy 210.82 175.26) (xy 219.71 175.26))
    (stroke (width 0) (type default))
  )
  (wire (pts (xy 219.71 246.38) (xy 219.71 248.92))
    (stroke (width 0) (type default))
  )
  (wire (pts (xy 125.73 97.79) (xy 148.59 97.79))
    (stroke (width 0) (type default))
  )
  (wire (pts (xy 114.3 60.96) (xy 116.84 60.96))
    (stroke (width 0) (type default))
  )
  (wire (pts (xy 90.17 200.66) (xy 92.71 200.66))
    (stroke (width 0) (type default))
  )
  (wire (pts (xy 231.14 198.12) (xy 231.14 200.66))
    (stroke (width 0) (type default))
  )
  (wire (pts (xy 231.14 228.6) (xy 231.14 231.14))
    (stroke (width 0) (type default))
  )
  (wire (pts (xy 219.71 152.4) (xy 219.71 154.94))
    (stroke (width 0) (type default))
  )
  (wire (pts (xy 198.12 175.26) (xy 198.12 144.78))
    (stroke (width 0) (type default))
  )
  (wire (pts (xy 210.82 220.345) (xy 210.82 220.98))
    (stroke (width 0) (type default))
  )
  (wire (pts (xy 307.34 83.82) (xy 307.34 86.36))
    (stroke (width 0) (type default))
  )
  (wire (pts (xy 219.71 205.74) (xy 231.14 205.74))
    (stroke (width 0) (type default))
  )
  (wire (pts (xy 114.3 45.72) (xy 114.3 53.34))
    (stroke (width 0) (type default))
  )
  (wire (pts (xy 327.66 100.33) (xy 335.28 100.33))
    (stroke (width 0) (type default))
  )
  (wire (pts (xy 233.68 175.26) (xy 236.22 175.26))
    (stroke (width 0) (type default))
  )
  (wire (pts (xy 331.47 208.28) (xy 330.2 208.28))
    (stroke (width 0) (type default))
  )
  (wire (pts (xy 360.68 83.82) (xy 355.6 83.82))
    (stroke (width 0) (type default))
  )
  (wire (pts (xy 358.14 171.45) (xy 358.14 175.26))
    (stroke (width 0) (type default))
  )
  (wire (pts (xy 180.34 215.9) (xy 195.58 215.9))
    (stroke (width 0) (type default))
  )
  (wire (pts (xy 89.535 78.74) (xy 89.535 80.01))
    (stroke (width 0) (type default))
  )
  (wire (pts (xy 26.67 53.34) (xy 48.26 53.34))
    (stroke (width 0) (type default))
  )
  (wire (pts (xy 337.82 43.18) (xy 336.55 43.18))
    (stroke (width 0) (type default))
  )
  (wire (pts (xy 231.14 190.5) (xy 231.14 193.04))
    (stroke (width 0) (type default))
  )
  (wire (pts (xy 149.86 52.07) (xy 166.37 52.07))
    (stroke (width 0) (type default))
  )
  (wire (pts (xy 106.68 240.03) (xy 85.09 240.03))
    (stroke (width 0) (type default))
  )
  (wire (pts (xy 219.71 144.78) (xy 228.6 144.78))
    (stroke (width 0) (type default))
  )
  (wire (pts (xy 97.79 73.66) (xy 116.84 73.66))
    (stroke (width 0) (type default))
  )
  (wire (pts (xy 97.79 78.74) (xy 116.84 78.74))
    (stroke (width 0) (type default))
  )
  (wire (pts (xy 316.23 38.1) (xy 316.23 40.64))
    (stroke (width 0) (type default))
  )
  (wire (pts (xy 236.22 143.51) (xy 236.22 144.78))
    (stroke (width 0) (type default))
  )
  (wire (pts (xy 307.34 83.82) (xy 318.77 83.82))
    (stroke (width 0) (type default))
  )
  (wire (pts (xy 231.14 220.98) (xy 245.11 220.98))
    (stroke (width 0) (type default))
  )
  (wire (pts (xy 210.185 144.145) (xy 210.185 144.78))
    (stroke (width 0) (type default))
  )
  (wire (pts (xy 318.77 83.82) (xy 318.77 87.63))
    (stroke (width 0) (type default))
  )
  (wire (pts (xy 360.68 100.33) (xy 388.62 100.33))
    (stroke (width 0) (type default))
  )
  (wire (pts (xy 106.68 247.65) (xy 104.14 247.65))
    (stroke (width 0) (type default))
  )
  (wire (pts (xy 38.1 167.64) (xy 59.69 167.64))
    (stroke (width 0) (type default))
  )
  (wire (pts (xy 330.2 203.2) (xy 330.2 205.74))
    (stroke (width 0) (type default))
  )
  (wire (pts (xy 149.86 57.15) (xy 166.37 57.15))
    (stroke (width 0) (type default))
  )
  (wire (pts (xy 26.67 33.02) (xy 48.26 33.02))
    (stroke (width 0) (type default))
  )
  (wire (pts (xy 97.79 43.18) (xy 116.84 43.18))
    (stroke (width 0) (type default))
  )
  (wire (pts (xy 369.57 102.87) (xy 388.62 102.87))
    (stroke (width 0) (type default))
  )
  (wire (pts (xy 375.92 38.1) (xy 382.27 38.1))
    (stroke (width 0) (type default))
  )
  (wire (pts (xy 330.2 171.45) (xy 331.47 171.45))
    (stroke (width 0) (type default))
  )
  (wire (pts (xy 90.17 157.48) (xy 104.14 157.48))
    (stroke (width 0) (type default))
  )
  (wire (pts (xy 149.86 49.53) (xy 166.37 49.53))
    (stroke (width 0) (type default))
  )
  (wire (pts (xy 152.4 193.04) (xy 152.4 198.12))
    (stroke (width 0) (type default))
  )
  (wire (pts (xy 85.09 240.03) (xy 85.09 254))
    (stroke (width 0) (type default))
  )
  (wire (pts (xy 210.82 189.865) (xy 210.82 190.5))
    (stroke (width 0) (type default))
  )
  (wire (pts (xy 180.34 185.42) (xy 182.245 185.42))
    (stroke (width 0) (type default))
  )
  (wire (pts (xy 330.835 38.1) (xy 326.39 38.1))
    (stroke (width 0) (type default))
  )
  (wire (pts (xy 250.19 205.74) (xy 254 205.74))
    (stroke (width 0) (type default))
  )
  (wire (pts (xy 188.595 218.44) (xy 189.865 218.44))
    (stroke (width 0) (type default))
  )
  (wire (pts (xy 318.77 83.82) (xy 327.66 83.82))
    (stroke (width 0) (type default))
  )
  (wire (pts (xy 114.3 53.34) (xy 116.84 53.34))
    (stroke (width 0) (type default))
  )
  (wire (pts (xy 97.79 48.26) (xy 116.84 48.26))
    (stroke (width 0) (type default))
  )
  (wire (pts (xy 104.14 247.65) (xy 104.14 254))
    (stroke (width 0) (type default))
  )
  (wire (pts (xy 125.73 97.79) (xy 125.73 97.155))
    (stroke (width 0) (type default))
  )
  (wire (pts (xy 336.55 40.64) (xy 336.55 38.1))
    (stroke (width 0) (type default))
  )
  (wire (pts (xy 90.17 172.72) (xy 104.14 172.72))
    (stroke (width 0) (type default))
  )
  (wire (pts (xy 326.39 45.72) (xy 326.39 48.26))
    (stroke (width 0) (type default))
  )
  (wire (pts (xy 38.1 165.1) (xy 59.69 165.1))
    (stroke (width 0) (type default))
  )
  (wire (pts (xy 26.67 73.66) (xy 48.26 73.66))
    (stroke (width 0) (type default))
  )
  (wire (pts (xy 201.93 160.02) (xy 210.82 160.02))
    (stroke (width 0) (type default))
  )
  (wire (pts (xy 26.67 48.26) (xy 48.26 48.26))
    (stroke (width 0) (type default))
  )
  (wire (pts (xy 149.86 67.31) (xy 166.37 67.31))
    (stroke (width 0) (type default))
  )
  (wire (pts (xy 381 81.28) (xy 381 83.82))
    (stroke (width 0) (type default))
  )
  (wire (pts (xy 337.82 40.64) (xy 336.55 40.64))
    (stroke (width 0) (type default))
  )
  (wire (pts (xy 312.42 38.1) (xy 316.23 38.1))
    (stroke (width 0) (type default))
  )
  (wire (pts (xy 73.66 68.58) (xy 89.535 68.58))
    (stroke (width 0) (type default))
  )
  (wire (pts (xy 359.41 205.74) (xy 358.14 205.74))
    (stroke (width 0) (type default))
  )
  (wire (pts (xy 293.37 102.87) (xy 318.77 102.87))
    (stroke (width 0) (type default))
  )
  (wire (pts (xy 336.55 38.1) (xy 330.835 38.1))
    (stroke (width 0) (type default))
  )
  (wire (pts (xy 353.06 102.87) (xy 369.57 102.87))
    (stroke (width 0) (type default))
  )
  (wire (pts (xy 330.2 181.61) (xy 330.2 184.15))
    (stroke (width 0) (type default))
  )
  (wire (pts (xy 149.86 62.23) (xy 166.37 62.23))
    (stroke (width 0) (type default))
  )
  (wire (pts (xy 250.19 238.76) (xy 254 238.76))
    (stroke (width 0) (type default))
  )
  (wire (pts (xy 198.12 144.78) (xy 210.185 144.78))
    (stroke (width 0) (type default))
  )
  (wire (pts (xy 152.4 193.04) (xy 154.94 193.04))
    (stroke (width 0) (type default))
  )
  (wire (pts (xy 182.88 182.88) (xy 182.245 182.88))
    (stroke (width 0) (type default))
  )
  (wire (pts (xy 90.17 180.34) (xy 104.14 180.34))
    (stroke (width 0) (type default))
  )
  (wire (pts (xy 231.14 220.98) (xy 231.14 223.52))
    (stroke (width 0) (type default))
  )
  (wire (pts (xy 307.34 91.44) (xy 307.34 93.98))
    (stroke (width 0) (type default))
  )
  (wire (pts (xy 210.82 238.76) (xy 219.71 238.76))
    (stroke (width 0) (type default))
  )
  (wire (pts (xy 114.3 76.2) (xy 116.84 76.2))
    (stroke (width 0) (type default))
  )
  (wire (pts (xy 330.2 168.91) (xy 330.2 171.45))
    (stroke (width 0) (type default))
  )
  (wire (pts (xy 101.6 97.79) (xy 114.3 97.79))
    (stroke (width 0) (type default))
  )
  (wire (pts (xy 73.66 78.74) (xy 89.535 78.74))
    (stroke (width 0) (type default))
  )
  (wire (pts (xy 76.2 81.28) (xy 73.66 81.28))
    (stroke (width 0) (type default))
  )
  (wire (pts (xy 188.595 218.44) (xy 188.595 225.425))
    (stroke (width 0) (type default))
  )
  (wire (pts (xy 292.1 45.72) (xy 292.1 48.26))
    (stroke (width 0) (type default))
  )
  (wire (pts (xy 38.1 157.48) (xy 59.69 157.48))
    (stroke (width 0) (type default))
  )
  (wire (pts (xy 180.34 175.26) (xy 198.12 175.26))
    (stroke (width 0) (type default))
  )
  (wire (pts (xy 89.535 76.2) (xy 89.535 78.74))
    (stroke (width 0) (type default))
  )
  (wire (pts (xy 210.82 190.5) (xy 219.71 190.5))
    (stroke (width 0) (type default))
  )
  (wire (pts (xy 330.2 205.74) (xy 331.47 205.74))
    (stroke (width 0) (type default))
  )
  (wire (pts (xy 180.34 205.74) (xy 201.93 205.74))
    (stroke (width 0) (type default))
  )
  (wire (pts (xy 89.535 71.12) (xy 89.535 73.66))
    (stroke (width 0) (type default))
  )
  (wire (pts (xy 201.93 205.74) (xy 201.93 220.98))
    (stroke (width 0) (type default))
  )
  (wire (pts (xy 233.68 160.02) (xy 236.22 160.02))
    (stroke (width 0) (type default))
  )
  (wire (pts (xy 330.2 173.99) (xy 330.2 176.53))
    (stroke (width 0) (type default))
  )
  (wire (pts (xy 73.66 73.66) (xy 89.535 73.66))
    (stroke (width 0) (type default))
  )
  (wire (pts (xy 26.67 30.48) (xy 48.26 30.48))
    (stroke (width 0) (type default))
  )
  (wire (pts (xy 89.535 73.66) (xy 89.535 76.2))
    (stroke (width 0) (type default))
  )
  (wire (pts (xy 38.1 170.18) (xy 59.69 170.18))
    (stroke (width 0) (type default))
  )
  (wire (pts (xy 337.82 38.1) (xy 336.55 38.1))
    (stroke (width 0) (type default))
  )
  (wire (pts (xy 85.09 259.08) (xy 85.09 261.62))
    (stroke (width 0) (type default))
  )
  (wire (pts (xy 330.2 208.28) (xy 330.2 205.74))
    (stroke (width 0) (type default))
  )
  (wire (pts (xy 330.2 208.28) (xy 330.2 210.82))
    (stroke (width 0) (type default))
  )
  (wire (pts (xy 182.88 49.53) (xy 185.42 49.53))
    (stroke (width 0) (type default))
  )
  (wire (pts (xy 236.22 160.02) (xy 236.22 175.26))
    (stroke (width 0) (type default))
  )
  (wire (pts (xy 152.4 198.12) (xy 152.4 223.52))
    (stroke (width 0) (type default))
  )
  (wire (pts (xy 332.74 97.79) (xy 335.28 97.79))
    (stroke (width 0) (type default))
  )
  (wire (pts (xy 219.71 167.64) (xy 219.71 170.18))
    (stroke (width 0) (type default))
  )
  (wire (pts (xy 38.1 180.34) (xy 59.69 180.34))
    (stroke (width 0) (type default))
  )
  (wire (pts (xy 326.39 38.1) (xy 326.39 40.64))
    (stroke (width 0) (type default))
  )
  (wire (pts (xy 231.14 213.36) (xy 231.14 215.9))
    (stroke (width 0) (type default))
  )
  (wire (pts (xy 152.4 171.45) (xy 152.4 175.26))
    (stroke (width 0) (type default))
  )
  (wire (pts (xy 76.2 81.28) (xy 76.2 82.55))
    (stroke (width 0) (type default))
  )
  (wire (pts (xy 369.57 83.82) (xy 360.68 83.82))
    (stroke (width 0) (type default))
  )
  (wire (pts (xy 330.2 215.9) (xy 330.2 218.44))
    (stroke (width 0) (type default))
  )
  (wire (pts (xy 180.34 198.12) (xy 205.74 198.12))
    (stroke (width 0) (type default))
  )
  (wire (pts (xy 182.88 218.44) (xy 182.88 223.52))
    (stroke (width 0) (type default))
  )
  (wire (pts (xy 38.1 162.56) (xy 59.69 162.56))
    (stroke (width 0) (type default))
  )
  (wire (pts (xy 97.79 66.04) (xy 116.84 66.04))
    (stroke (width 0) (type default))
  )
  (wire (pts (xy 360.68 83.82) (xy 360.68 87.63))
    (stroke (width 0) (type default))
  )
  (wire (pts (xy 356.87 38.1) (xy 364.49 38.1))
    (stroke (width 0) (type default))
  )
  (wire (pts (xy 231.14 246.38) (xy 231.14 248.92))
    (stroke (width 0) (type default))
  )
  (wire (pts (xy 97.79 50.8) (xy 116.84 50.8))
    (stroke (width 0) (type default))
  )
  (wire (pts (xy 114.3 45.72) (xy 116.84 45.72))
    (stroke (width 0) (type default))
  )
  (wire (pts (xy 73.66 76.2) (xy 89.535 76.2))
    (stroke (width 0) (type default))
  )
  (wire (pts (xy 236.22 144.78) (xy 236.22 160.02))
    (stroke (width 0) (type default))
  )
  (wire (pts (xy 358.14 205.74) (xy 358.14 209.55))
    (stroke (width 0) (type default))
  )
  (wire (pts (xy 76.2 87.63) (xy 76.2 90.17))
    (stroke (width 0) (type default))
  )
  (wire (pts (xy 104.14 259.08) (xy 104.14 261.62))
    (stroke (width 0) (type default))
  )
  (wire (pts (xy 369.57 92.71) (xy 369.57 102.87))
    (stroke (width 0) (type default))
  )
  (wire (pts (xy 219.71 220.98) (xy 219.71 223.52))
    (stroke (width 0) (type default))
  )
  (wire (pts (xy 101.6 104.14) (xy 114.3 104.14))
    (stroke (width 0) (type default))
  )
  (wire (pts (xy 219.71 238.76) (xy 219.71 241.3))
    (stroke (width 0) (type default))
  )
  (wire (pts (xy 360.68 100.33) (xy 353.06 100.33))
    (stroke (width 0) (type default))
  )
  (wire (pts (xy 219.71 175.26) (xy 219.71 177.8))
    (stroke (width 0) (type default))
  )
  (wire (pts (xy 90.17 177.8) (xy 104.14 177.8))
    (stroke (width 0) (type default))
  )
  (wire (pts (xy 327.66 83.82) (xy 327.66 87.63))
    (stroke (width 0) (type default))
  )
  (wire (pts (xy 219.71 213.36) (xy 219.71 215.9))
    (stroke (width 0) (type default))
  )
  (wire (pts (xy 382.27 45.72) (xy 382.27 48.26))
    (stroke (width 0) (type default))
  )
  (wire (pts (xy 382.27 38.1) (xy 396.24 38.1))
    (stroke (width 0) (type default))
  )
  (wire (pts (xy 353.06 175.26) (xy 353.06 173.99))
    (stroke (width 0) (type default))
  )
  (wire (pts (xy 293.37 100.33) (xy 327.66 100.33))
    (stroke (width 0) (type default))
  )
  (wire (pts (xy 90.17 160.02) (xy 104.14 160.02))
    (stroke (width 0) (type default))
  )
  (wire (pts (xy 26.67 38.1) (xy 48.26 38.1))
    (stroke (width 0) (type default))
  )
  (wire (pts (xy 89.535 68.58) (xy 89.535 71.12))
    (stroke (width 0) (type default))
  )
  (wire (pts (xy 90.17 175.26) (xy 104.14 175.26))
    (stroke (width 0) (type default))
  )
  (wire (pts (xy 185.42 67.31) (xy 185.42 69.85))
    (stroke (width 0) (type default))
  )
  (wire (pts (xy 210.82 174.625) (xy 210.82 175.26))
    (stroke (width 0) (type default))
  )
  (wire (pts (xy 152.4 198.12) (xy 154.94 198.12))
    (stroke (width 0) (type default))
  )
  (wire (pts (xy 182.88 218.44) (xy 188.595 218.44))
    (stroke (width 0) (type default))
  )
  (wire (pts (xy 302.26 38.1) (xy 302.26 40.64))
    (stroke (width 0) (type default))
  )
  (wire (pts (xy 353.06 209.55) (xy 353.06 208.28))
    (stroke (width 0) (type default))
  )
  (wire (pts (xy 26.67 60.96) (xy 48.26 60.96))
    (stroke (width 0) (type default))
  )
  (wire (pts (xy 219.71 220.98) (xy 231.14 220.98))
    (stroke (width 0) (type default))
  )
  (wire (pts (xy 292.1 38.1) (xy 292.1 40.64))
    (stroke (width 0) (type default))
  )
  (wire (pts (xy 364.49 45.72) (xy 364.49 48.26))
    (stroke (width 0) (type default))
  )
  (wire (pts (xy 114.3 76.2) (xy 114.3 84.455))
    (stroke (width 0) (type default))
  )
  (wire (pts (xy 198.12 238.76) (xy 210.82 238.76))
    (stroke (width 0) (type default))
  )
  (wire (pts (xy 198.12 215.9) (xy 198.12 238.76))
    (stroke (width 0) (type default))
  )
  (wire (pts (xy 90.17 167.64) (xy 104.14 167.64))
    (stroke (width 0) (type default))
  )
  (wire (pts (xy 360.68 92.71) (xy 360.68 100.33))
    (stroke (width 0) (type default))
  )
  (wire (pts (xy 97.79 68.58) (xy 116.84 68.58))
    (stroke (width 0) (type default))
  )
  (wire (pts (xy 73.66 71.12) (xy 89.535 71.12))
    (stroke (width 0) (type default))
  )
  (wire (pts (xy 26.67 45.72) (xy 48.26 45.72))
    (stroke (width 0) (type default))
  )
  (wire (pts (xy 369.57 83.82) (xy 369.57 87.63))
    (stroke (width 0) (type default))
  )
  (wire (pts (xy 307.34 81.28) (xy 307.34 83.82))
    (stroke (width 0) (type default))
  )
  (wire (pts (xy 205.74 205.74) (xy 205.74 198.12))
    (stroke (width 0) (type default))
  )
  (wire (pts (xy 302.26 45.72) (xy 302.26 48.26))
    (stroke (width 0) (type default))
  )
  (wire (pts (xy 210.82 205.105) (xy 210.82 205.74))
    (stroke (width 0) (type default))
  )
  (wire (pts (xy 336.55 43.18) (xy 336.55 45.085))
    (stroke (width 0) (type default))
  )
  (wire (pts (xy 330.835 37.465) (xy 330.835 38.1))
    (stroke (width 0) (type default))
  )
  (wire (pts (xy 219.71 205.74) (xy 219.71 208.28))
    (stroke (width 0) (type default))
  )
  (wire (pts (xy 152.4 152.4) (xy 152.4 166.37))
    (stroke (width 0) (type default))
  )
  (wire (pts (xy 180.34 190.5) (xy 210.82 190.5))
    (stroke (width 0) (type default))
  )
  (wire (pts (xy 195.58 215.9) (xy 198.12 215.9))
    (stroke (width 0) (type default))
  )
  (wire (pts (xy 152.4 175.26) (xy 154.94 175.26))
    (stroke (width 0) (type default))
  )
  (wire (pts (xy 90.17 190.5) (xy 104.14 190.5))
    (stroke (width 0) (type default))
  )
  (wire (pts (xy 219.71 190.5) (xy 231.14 190.5))
    (stroke (width 0) (type default))
  )
  (wire (pts (xy 182.245 185.42) (xy 205.74 185.42))
    (stroke (width 0) (type default))
  )
  (wire (pts (xy 114.3 60.96) (xy 114.3 76.2))
    (stroke (width 0) (type default))
  )
  (wire (pts (xy 254 220.98) (xy 254 238.76))
    (stroke (width 0) (type default))
  )
  (wire (pts (xy 316.23 45.72) (xy 316.23 48.26))
    (stroke (width 0) (type default))
  )
  (wire (pts (xy 231.14 205.74) (xy 245.11 205.74))
    (stroke (width 0) (type default))
  )
  (wire (pts (xy 353.06 173.99) (xy 351.79 173.99))
    (stroke (width 0) (type default))
  )
  (wire (pts (xy 146.05 180.34) (xy 154.94 180.34))
    (stroke (width 0) (type default))
  )
  (wire (pts (xy 149.86 54.61) (xy 166.37 54.61))
    (stroke (width 0) (type default))
  )
  (wire (pts (xy 210.82 159.385) (xy 210.82 160.02))
    (stroke (width 0) (type default))
  )
  (wire (pts (xy 381 83.82) (xy 381 86.36))
    (stroke (width 0) (type default))
  )
  (wire (pts (xy 154.94 190.5) (xy 152.4 190.5))
    (stroke (width 0) (type default))
  )
  (wire (pts (xy 219.71 190.5) (xy 219.71 193.04))
    (stroke (width 0) (type default))
  )
  (wire (pts (xy 233.68 144.78) (xy 236.22 144.78))
    (stroke (width 0) (type default))
  )
  (wire (pts (xy 119.38 97.79) (xy 121.92 97.79))
    (stroke (width 0) (type default))
  )
  (wire (pts (xy 90.17 185.42) (xy 104.14 185.42))
    (stroke (width 0) (type default))
  )
  (wire (pts (xy 205.74 175.26) (xy 210.82 175.26))
    (stroke (width 0) (type default))
  )
  (wire (pts (xy 358.14 180.34) (xy 358.14 184.15))
    (stroke (width 0) (type default))
  )
  (wire (pts (xy 358.14 171.45) (xy 351.79 171.45))
    (stroke (width 0) (type default))
  )
  (wire (pts (xy 231.14 238.76) (xy 245.11 238.76))
    (stroke (width 0) (type default))
  )
  (wire (pts (xy 201.93 160.02) (xy 201.93 177.8))
    (stroke (width 0) (type default))
  )
  (wire (pts (xy 210.82 160.02) (xy 219.71 160.02))
    (stroke (width 0) (type default))
  )
  (wire (pts (xy 327.66 83.82) (xy 332.74 83.82))
    (stroke (width 0) (type default))
  )
  (wire (pts (xy 97.79 40.64) (xy 116.84 40.64))
    (stroke (width 0) (type default))
  )
  (wire (pts (xy 332.74 83.82) (xy 332.74 97.79))
    (stroke (width 0) (type default))
  )
  (wire (pts (xy 210.185 144.78) (xy 219.71 144.78))
    (stroke (width 0) (type default))
  )
  (wire (pts (xy 219.71 144.78) (xy 219.71 147.32))
    (stroke (width 0) (type default))
  )
  (wire (pts (xy 93.98 259.08) (xy 93.98 261.62))
    (stroke (width 0) (type default))
  )
  (wire (pts (xy 121.92 97.79) (xy 125.73 97.79))
    (stroke (width 0) (type default))
  )
  (wire (pts (xy 219.71 160.02) (xy 219.71 162.56))
    (stroke (width 0) (type default))
  )
  (wire (pts (xy 149.86 59.69) (xy 166.37 59.69))
    (stroke (width 0) (type default))
  )
  (wire (pts (xy 219.71 238.76) (xy 231.14 238.76))
    (stroke (width 0) (type default))
  )
  (wire (pts (xy 93.98 242.57) (xy 106.68 242.57))
    (stroke (width 0) (type default))
  )
  (wire (pts (xy 355.6 83.82) (xy 355.6 97.79))
    (stroke (width 0) (type default))
  )
  (wire (pts (xy 219.71 228.6) (xy 219.71 231.14))
    (stroke (width 0) (type default))
  )
  (wire (pts (xy 219.71 220.98) (xy 210.82 220.98))
    (stroke (width 0) (type default))
  )
  (wire (pts (xy 38.1 172.72) (xy 59.69 172.72))
    (stroke (width 0) (type default))
  )
  (wire (pts (xy 219.71 160.02) (xy 228.6 160.02))
    (stroke (width 0) (type default))
  )
  (wire (pts (xy 254 205.74) (xy 255.27 205.74))
    (stroke (width 0) (type default))
  )
  (wire (pts (xy 26.67 40.64) (xy 48.26 40.64))
    (stroke (width 0) (type default))
  )
  (wire (pts (xy 38.1 200.66) (xy 59.69 200.66))
    (stroke (width 0) (type default))
  )
  (wire (pts (xy 335.28 102.87) (xy 318.77 102.87))
    (stroke (width 0) (type default))
  )
  (wire (pts (xy 327.66 92.71) (xy 327.66 100.33))
    (stroke (width 0) (type default))
  )
  (wire (pts (xy 355.6 97.79) (xy 353.06 97.79))
    (stroke (width 0) (type default))
  )
  (wire (pts (xy 121.92 97.79) (xy 121.92 104.14))
    (stroke (width 0) (type default))
  )
  (wire (pts (xy 231.14 190.5) (xy 245.11 190.5))
    (stroke (width 0) (type default))
  )
  (wire (pts (xy 142.24 182.88) (xy 154.94 182.88))
    (stroke (width 0) (type default))
  )
  (wire (pts (xy 114.3 53.34) (xy 114.3 60.96))
    (stroke (width 0) (type default))
  )
  (wire (pts (xy 90.17 203.2) (xy 92.71 203.2))
    (stroke (width 0) (type default))
  )
  (wire (pts (xy 180.34 218.44) (xy 182.88 218.44))
    (stroke (width 0) (type default))
  )
  (wire (pts (xy 358.14 171.45) (xy 359.41 171.45))
    (stroke (width 0) (type default))
  )
  (wire (pts (xy 116.84 38.1) (xy 114.3 38.1))
    (stroke (width 0) (type default))
  )
  (wire (pts (xy 97.79 35.56) (xy 116.84 35.56))
    (stroke (width 0) (type default))
  )
  (wire (pts (xy 292.1 36.83) (xy 292.1 38.1))
    (stroke (width 0) (type default))
  )
  (wire (pts (xy 219.71 205.74) (xy 210.82 205.74))
    (stroke (width 0) (type default))
  )
  (wire (pts (xy 353.06 208.28) (xy 351.79 208.28))
    (stroke (width 0) (type default))
  )
  (wire (pts (xy 97.79 71.12) (xy 116.84 71.12))
    (stroke (width 0) (type default))
  )
  (wire (pts (xy 26.67 68.58) (xy 48.26 68.58))
    (stroke (width 0) (type default))
  )
  (wire (pts (xy 318.77 92.71) (xy 318.77 102.87))
    (stroke (width 0) (type default))
  )
  (wire (pts (xy 113.665 84.455) (xy 114.3 84.455))
    (stroke (width 0) (type default))
  )
  (wire (pts (xy 231.14 205.74) (xy 231.14 208.28))
    (stroke (width 0) (type default))
  )
  (wire (pts (xy 90.17 162.56) (xy 104.14 162.56))
    (stroke (width 0) (type default))
  )
  (wire (pts (xy 38.1 175.26) (xy 59.69 175.26))
    (stroke (width 0) (type default))
  )
  (wire (pts (xy 250.19 190.5) (xy 255.27 190.5))
    (stroke (width 0) (type default))
  )
  (wire (pts (xy 381 91.44) (xy 381 93.98))
    (stroke (width 0) (type default))
  )
  (wire (pts (xy 93.98 242.57) (xy 93.98 254))
    (stroke (width 0) (type default))
  )
  (wire (pts (xy 26.67 81.28) (xy 48.26 81.28))
    (stroke (width 0) (type default))
  )
  (wire (pts (xy 38.1 203.2) (xy 59.69 203.2))
    (stroke (width 0) (type default))
  )
  (wire (pts (xy 146.05 171.45) (xy 146.05 180.34))
    (stroke (width 0) (type default))
  )
  (wire (pts (xy 302.26 38.1) (xy 292.1 38.1))
    (stroke (width 0) (type default))
  )
  (wire (pts (xy 364.49 38.1) (xy 364.49 40.64))
    (stroke (width 0) (type default))
  )
  (wire (pts (xy 381 83.82) (xy 369.57 83.82))
    (stroke (width 0) (type default))
  )
  (wire (pts (xy 114.3 38.1) (xy 114.3 45.72))
    (stroke (width 0) (type default))
  )
  (wire (pts (xy 38.1 185.42) (xy 59.69 185.42))
    (stroke (width 0) (type default))
  )
  (wire (pts (xy 135.89 180.34) (xy 146.05 180.34))
    (stroke (width 0) (type default))
  )
  (wire (pts (xy 146.05 162.56) (xy 146.05 166.37))
    (stroke (width 0) (type default))
  )
  (wire (pts (xy 330.2 173.99) (xy 330.2 171.45))
    (stroke (width 0) (type default))
  )
  (wire (pts (xy 358.14 214.63) (xy 358.14 218.44))
    (stroke (width 0) (type default))
  )
  (wire (pts (xy 358.14 205.74) (xy 351.79 205.74))
    (stroke (width 0) (type default))
  )
  (wire (pts (xy 90.17 170.18) (xy 104.14 170.18))
    (stroke (width 0) (type default))
  )
  (wire (pts (xy 97.79 81.28) (xy 116.84 81.28))
    (stroke (width 0) (type default))
  )
  (wire (pts (xy 201.93 220.98) (xy 210.82 220.98))
    (stroke (width 0) (type default))
  )
  (wire (pts (xy 250.19 220.98) (xy 254 220.98))
    (stroke (width 0) (type default))
  )
  (wire (pts (xy 185.42 46.99) (xy 185.42 49.53))
    (stroke (width 0) (type default))
  )
  (wire (pts (xy 353.06 105.41) (xy 355.6 105.41))
    (stroke (width 0) (type default))
  )
  (wire (pts (xy 182.88 67.31) (xy 185.42 67.31))
    (stroke (width 0) (type default))
  )
  (wire (pts (xy 182.88 228.6) (xy 182.88 231.14))
    (stroke (width 0) (type default))
  )
  (wire (pts (xy 219.71 175.26) (xy 228.6 175.26))
    (stroke (width 0) (type default))
  )
  (wire (pts (xy 382.27 38.1) (xy 382.27 40.64))
    (stroke (width 0) (type default))
  )
  (wire (pts (xy 149.86 64.77) (xy 166.37 64.77))
    (stroke (width 0) (type default))
  )
  (wire (pts (xy 326.39 38.1) (xy 316.23 38.1))
    (stroke (width 0) (type default))
  )
  (wire (pts (xy 90.17 165.1) (xy 104.14 165.1))
    (stroke (width 0) (type default))
  )
  (wire (pts (xy 97.79 55.88) (xy 116.84 55.88))
    (stroke (width 0) (type default))
  )
  (wire (pts (xy 302.26 38.1) (xy 307.34 38.1))
    (stroke (width 0) (type default))
  )
  (wire (pts (xy 219.71 198.12) (xy 219.71 200.66))
    (stroke (width 0) (type default))
  )
  (wire (pts (xy 254 205.74) (xy 254 220.98))
    (stroke (width 0) (type default))
  )
  (wire (pts (xy 152.4 190.5) (xy 152.4 193.04))
    (stroke (width 0) (type default))
  )
  (wire (pts (xy 26.67 76.2) (xy 48.26 76.2))
    (stroke (width 0) (type default))
  )
  (wire (pts (xy 231.14 238.76) (xy 231.14 241.3))
    (stroke (width 0) (type default))
  )
  (wire (pts (xy 364.49 38.1) (xy 370.84 38.1))
    (stroke (width 0) (type default))
  )
  (wire (pts (xy 331.47 173.99) (xy 330.2 173.99))
    (stroke (width 0) (type default))
  )
  (wire (pts (xy 210.82 238.125) (xy 210.82 238.76))
    (stroke (width 0) (type default))
  )

  (text "Video Interfaces" (at 60.96 144.78 0)
    (effects (font (size 2.54 2.54)) (justify left bottom))
  )
  (text "88mA" (at 189.23 185.42 0)
    (effects (font (size 1.27 1.27)) (justify left bottom))
  )
  (text "Converter IC" (at 116.84 132.08 0)
    (effects (font (size 4 4)) (justify left bottom))
  )
  (text "1V2" (at 181.61 195.58 0)
    (effects (font (size 1.27 1.27)) (justify left bottom))
  )
  (text "76mA" (at 186.69 215.9 0)
    (effects (font (size 1.27 1.27)) (justify left bottom))
  )
  (text "1V2" (at 181.61 215.9 0)
    (effects (font (size 1.27 1.27)) (justify left bottom))
  )
  (text "1V8-3V3" (at 181.61 177.8 0)
    (effects (font (size 1.27 1.27)) (justify left bottom))
  )
  (text "1V2" (at 181.61 218.44 0)
    (effects (font (size 1.27 1.27)) (justify left bottom))
  )
  (text "I2C Level Shifter" (at 320.04 73.66 0)
    (effects (font (size 4 4)) (justify left bottom))
  )
  (text "1V8-3V3" (at 181.61 175.26 0)
    (effects (font (size 1.27 1.27)) (justify left bottom))
  )
  (text "9mA" (at 191.77 177.8 0)
    (effects (font (size 1.27 1.27)) (justify left bottom))
  )
  (text "1V2" (at 181.61 205.74 0)
    (effects (font (size 1.27 1.27)) (justify left bottom))
  )
  (text "2V5" (at 181.61 190.5 0)
    (effects (font (size 1.27 1.27)) (justify left bottom))
  )
  (text "Connectors" (at 93.98 24.13 0)
    (effects (font (size 4 4)) (justify left bottom))
  )
  (text "13mA" (at 186.69 190.5 0)
    (effects (font (size 1.27 1.27)) (justify left bottom))
  )
  (text "CH1_INT" (at 142.24 185.42 0)
    (effects (font (size 1.27 1.27)) (justify left bottom))
  )
  (text "Voltage Regulators" (at 314.96 152.4 0)
    (effects (font (size 4 4)) (justify left bottom))
  )
  (text "3V3" (at 184.15 185.42 0)
    (effects (font (size 1.27 1.27)) (justify left bottom))
  )
  (text "27MHz Oscillator" (at 321.31 24.13 0)
    (effects (font (size 4 4)) (justify left bottom))
  )
  (text "Power" (at 162.56 160.02 0)
    (effects (font (size 2.54 2.54)) (justify left bottom))
  )
  (text "23mA" (at 186.69 205.74 0)
    (effects (font (size 1.27 1.27)) (justify left bottom))
  )
  (text "Misc" (at 104.14 222.25 0)
    (effects (font (size 2.54 2.54)) (justify left bottom))
  )
  (text "83mA" (at 186.69 195.58 0)
    (effects (font (size 1.27 1.27)) (justify left bottom))
  )

  (label "HDMI1_D2_P" (at 26.67 30.48 0) (fields_autoplaced)
    (effects (font (size 1.27 1.27)) (justify left bottom))
  )
  (label "HDMI1_CLK_N" (at 26.67 55.88 0) (fields_autoplaced)
    (effects (font (size 1.27 1.27)) (justify left bottom))
  )
  (label "HDMI1_CLK_N" (at 97.79 63.5 0) (fields_autoplaced)
    (effects (font (size 1.27 1.27)) (justify left bottom))
  )
  (label "HDMI1_CLK_P" (at 26.67 53.34 0) (fields_autoplaced)
    (effects (font (size 1.27 1.27)) (justify left bottom))
  )
  (label "HDMI1_CLK_P" (at 97.79 58.42 0) (fields_autoplaced)
    (effects (font (size 1.27 1.27)) (justify left bottom))
  )
  (label "HDMI1_HPD" (at 97.79 81.28 0) (fields_autoplaced)
    (effects (font (size 1.27 1.27)) (justify left bottom))
  )
  (label "HDMI1_CEC" (at 38.1 180.34 0) (fields_autoplaced)
    (effects (font (size 1.27 1.27)) (justify left bottom))
  )
  (label "HDMI1_D1_N" (at 38.1 170.18 0) (fields_autoplaced)
    (effects (font (size 1.27 1.27)) (justify left bottom))
  )
  (label "HDMI1_D2_P" (at 97.79 35.56 0) (fields_autoplaced)
    (effects (font (size 1.27 1.27)) (justify left bottom))
  )
  (label "HDMI1_D0_P" (at 97.79 50.8 0) (fields_autoplaced)
    (effects (font (size 1.27 1.27)) (justify left bottom))
  )
  (label "HDMI1_D0_N" (at 38.1 165.1 0) (fields_autoplaced)
    (effects (font (size 1.27 1.27)) (justify left bottom))
  )
  (label "CH1_REFCLK" (at 396.24 38.1 180) (fields_autoplaced)
    (effects (font (size 1.27 1.27)) (justify right bottom))
  )
  (label "CH1_REFCLK" (at 142.24 182.88 0) (fields_autoplaced)
    (effects (font (size 1.27 1.27)) (justify left bottom))
  )
  (label "HDMI1_D1_N" (at 97.79 48.26 0) (fields_autoplaced)
    (effects (font (size 1.27 1.27)) (justify left bottom))
  )
  (label "HDMI1_HPD" (at 101.6 97.79 0) (fields_autoplaced)
    (effects (font (size 1.27 1.27)) (justify left bottom))
  )
  (label "HDMI1_D2_N" (at 38.1 175.26 0) (fields_autoplaced)
    (effects (font (size 1.27 1.27)) (justify left bottom))
  )
  (label "HDMI1_CLK_N" (at 38.1 160.02 0) (fields_autoplaced)
    (effects (font (size 1.27 1.27)) (justify left bottom))
  )
  (label "HDMI1_D2_N" (at 149.86 52.07 0) (fields_autoplaced)
    (effects (font (size 1.27 1.27)) (justify left bottom))
  )
  (label "HDMI1_HPDO" (at 104.14 185.42 180) (fields_autoplaced)
    (effects (font (size 1.27 1.27)) (justify right bottom))
  )
  (label "HDMI1_POWER" (at 148.59 97.79 180) (fields_autoplaced)
    (effects (font (size 1.27 1.27)) (justify right bottom))
  )
  (label "CH1_~{RST}" (at 135.89 180.34 0) (fields_autoplaced)
    (effects (font (size 1.27 1.27)) (justify left bottom))
  )
  (label "CH1_AVDD33" (at 182.88 182.88 0) (fields_autoplaced)
    (effects (font (size 1.27 1.27)) (justify left bottom))
  )
  (label "HDMI1_D0_P" (at 149.86 59.69 0) (fields_autoplaced)
    (effects (font (size 1.27 1.27)) (justify left bottom))
  )
  (label "HDMI1_D0_P" (at 38.1 162.56 0) (fields_autoplaced)
    (effects (font (size 1.27 1.27)) (justify left bottom))
  )
  (label "HDMI1_POWER" (at 97.79 78.74 0) (fields_autoplaced)
    (effects (font (size 1.27 1.27)) (justify left bottom))
  )
  (label "HDMI1_CEC" (at 26.67 68.58 0) (fields_autoplaced)
    (effects (font (size 1.27 1.27)) (justify left bottom))
  )
  (label "HDMI1_DDC_SCL" (at 26.67 60.96 0) (fields_autoplaced)
    (effects (font (size 1.27 1.27)) (justify left bottom))
  )
  (label "HDMI1_D2_P" (at 149.86 49.53 0) (fields_autoplaced)
    (effects (font (size 1.27 1.27)) (justify left bottom))
  )
  (label "HDMI1_POWER" (at 26.67 81.28 0) (fields_autoplaced)
    (effects (font (size 1.27 1.27)) (justify left bottom))
  )
  (label "HDMI1_DDC_SCL" (at 388.62 100.33 180) (fields_autoplaced)
    (effects (font (size 1.27 1.27)) (justify right bottom))
  )
  (label "HDMI1_CLK_P" (at 38.1 157.48 0) (fields_autoplaced)
    (effects (font (size 1.27 1.27)) (justify left bottom))
  )
  (label "HDMI1_DDC_SCL" (at 97.79 71.12 0) (fields_autoplaced)
    (effects (font (size 1.27 1.27)) (justify left bottom))
  )
  (label "HDMI1_D1_P" (at 149.86 54.61 0) (fields_autoplaced)
    (effects (font (size 1.27 1.27)) (justify left bottom))
  )
  (label "HDMI1_D0_N" (at 97.79 55.88 0) (fields_autoplaced)
    (effects (font (size 1.27 1.27)) (justify left bottom))
  )
  (label "HDMI1_CLK_P" (at 149.86 64.77 0) (fields_autoplaced)
    (effects (font (size 1.27 1.27)) (justify left bottom))
  )
  (label "HDMI1_DDC_SDA" (at 97.79 73.66 0) (fields_autoplaced)
    (effects (font (size 1.27 1.27)) (justify left bottom))
  )
  (label "HDMI1_DDC_SCL_3V3" (at 293.37 100.33 0) (fields_autoplaced)
    (effects (font (size 1.27 1.27)) (justify left bottom))
  )
  (label "HDMI1_D0_P" (at 26.67 45.72 0) (fields_autoplaced)
    (effects (font (size 1.27 1.27)) (justify left bottom))
  )
  (label "DUMMY1" (at 26.67 76.2 0) (fields_autoplaced)
    (effects (font (size 1.27 1.27)) (justify left bottom))
  )
  (label "HDMI1_D0_N" (at 26.67 48.26 0) (fields_autoplaced)
    (effects (font (size 1.27 1.27)) (justify left bottom))
  )
  (label "HDMI1_D1_P" (at 26.67 38.1 0) (fields_autoplaced)
    (effects (font (size 1.27 1.27)) (justify left bottom))
  )
  (label "HDMI1_D1_N" (at 149.86 57.15 0) (fields_autoplaced)
    (effects (font (size 1.27 1.27)) (justify left bottom))
  )
  (label "HDMI1_D2_N" (at 26.67 33.02 0) (fields_autoplaced)
    (effects (font (size 1.27 1.27)) (justify left bottom))
  )
  (label "HDMI1_DDC_SDA" (at 388.62 102.87 180) (fields_autoplaced)
    (effects (font (size 1.27 1.27)) (justify right bottom))
  )
  (label "HDMI1_CEC" (at 97.79 66.04 0) (fields_autoplaced)
    (effects (font (size 1.27 1.27)) (justify left bottom))
  )
  (label "HDMI1_DDC_SCL_3V3" (at 38.1 203.2 0) (fields_autoplaced)
    (effects (font (size 1.27 1.27)) (justify left bottom))
  )
  (label "HDMI1_D1_P" (at 97.79 43.18 0) (fields_autoplaced)
    (effects (font (size 1.27 1.27)) (justify left bottom))
  )
  (label "HDMI1_D2_P" (at 38.1 172.72 0) (fields_autoplaced)
    (effects (font (size 1.27 1.27)) (justify left bottom))
  )
  (label "DUMMY1" (at 97.79 68.58 0) (fields_autoplaced)
    (effects (font (size 1.27 1.27)) (justify left bottom))
  )
  (label "CH1_AVDD33" (at 152.4 152.4 270) (fields_autoplaced)
    (effects (font (size 1.27 1.27)) (justify right bottom))
  )
  (label "HDMI1_DDC_SDA" (at 26.67 63.5 0) (fields_autoplaced)
    (effects (font (size 1.27 1.27)) (justify left bottom))
  )
  (label "HDMI1_D1_N" (at 26.67 40.64 0) (fields_autoplaced)
    (effects (font (size 1.27 1.27)) (justify left bottom))
  )
  (label "HDMI1_HPDI" (at 101.6 104.14 0) (fields_autoplaced)
    (effects (font (size 1.27 1.27)) (justify left bottom))
  )
  (label "HDMI1_CLK_N" (at 149.86 67.31 0) (fields_autoplaced)
    (effects (font (size 1.27 1.27)) (justify left bottom))
  )
  (label "HDMI1_DDC_SDA_3V3" (at 293.37 102.87 0) (fields_autoplaced)
    (effects (font (size 1.27 1.27)) (justify left bottom))
  )
  (label "HDMI1_HPDI" (at 38.1 185.42 0) (fields_autoplaced)
    (effects (font (size 1.27 1.27)) (justify left bottom))
  )
  (label "HDMI1_HPD" (at 26.67 73.66 0) (fields_autoplaced)
    (effects (font (size 1.27 1.27)) (justify left bottom))
  )
  (label "HDMI1_D0_N" (at 149.86 62.23 0) (fields_autoplaced)
    (effects (font (size 1.27 1.27)) (justify left bottom))
  )
  (label "HDMI1_D2_N" (at 97.79 40.64 0) (fields_autoplaced)
    (effects (font (size 1.27 1.27)) (justify left bottom))
  )
  (label "HDMI1_DDC_SDA_3V3" (at 38.1 200.66 0) (fields_autoplaced)
    (effects (font (size 1.27 1.27)) (justify left bottom))
  )
  (label "HDMI1_D1_P" (at 38.1 167.64 0) (fields_autoplaced)
    (effects (font (size 1.27 1.27)) (justify left bottom))
  )

  (global_label "CH1_2V5" (shape input) (at 255.27 190.5 0) (fields_autoplaced)
    (effects (font (size 1.27 1.27)) (justify left))
    (property "Intersheetrefs" "${INTERSHEET_REFS}" (at 265.9683 190.4206 0)
      (effects (font (size 1.27 1.27)) (justify left) hide)
    )
  )
  (global_label "CSI1_D2_P" (shape input) (at 104.14 167.64 0) (fields_autoplaced)
    (effects (font (size 1.27 1.27)) (justify left))
    (property "Intersheetrefs" "${INTERSHEET_REFS}" (at 116.5317 167.5606 0)
      (effects (font (size 1.27 1.27)) (justify left) hide)
    )
  )
  (global_label "CSI1_CLK_P" (shape input) (at 104.14 157.48 0) (fields_autoplaced)
    (effects (font (size 1.27 1.27)) (justify left))
    (property "Intersheetrefs" "${INTERSHEET_REFS}" (at 117.6202 157.4006 0)
      (effects (font (size 1.27 1.27)) (justify left) hide)
    )
  )
  (global_label "I2C1_SCL" (shape input) (at 104.14 193.04 0) (fields_autoplaced)
    (effects (font (size 1.27 1.27)) (justify left))
    (property "Intersheetrefs" "${INTERSHEET_REFS}" (at 115.3221 192.9606 0)
      (effects (font (size 1.27 1.27)) (justify left) hide)
    )
  )
  (global_label "CSI1_D3_P" (shape input) (at 104.14 172.72 0) (fields_autoplaced)
    (effects (font (size 1.27 1.27)) (justify left))
    (property "Intersheetrefs" "${INTERSHEET_REFS}" (at 116.5317 172.6406 0)
      (effects (font (size 1.27 1.27)) (justify left) hide)
    )
  )
  (global_label "CSI1_D4_N" (shape input) (at 104.14 180.34 0) (fields_autoplaced)
    (effects (font (size 1.27 1.27)) (justify left))
    (property "Intersheetrefs" "${INTERSHEET_REFS}" (at 116.5921 180.2606 0)
      (effects (font (size 1.27 1.27)) (justify left) hide)
    )
  )
  (global_label "CH1_1V2" (shape input) (at 359.41 205.74 0) (fields_autoplaced)
    (effects (font (size 1.27 1.27)) (justify left))
    (property "Intersheetrefs" "${INTERSHEET_REFS}" (at 370.1083 205.6606 0)
      (effects (font (size 1.27 1.27)) (justify left) hide)
    )
  )
  (global_label "CSI1_D3_N" (shape input) (at 104.14 175.26 0) (fields_autoplaced)
    (effects (font (size 1.27 1.27)) (justify left))
    (property "Intersheetrefs" "${INTERSHEET_REFS}" (at 116.5921 175.1806 0)
      (effects (font (size 1.27 1.27)) (justify left) hide)
    )
  )
  (global_label "CSI1_D2_N" (shape input) (at 104.14 170.18 0) (fields_autoplaced)
    (effects (font (size 1.27 1.27)) (justify left))
    (property "Intersheetrefs" "${INTERSHEET_REFS}" (at 116.5921 170.1006 0)
      (effects (font (size 1.27 1.27)) (justify left) hide)
    )
  )
  (global_label "CH1_2V5" (shape input) (at 359.41 171.45 0) (fields_autoplaced)
    (effects (font (size 1.27 1.27)) (justify left))
    (property "Intersheetrefs" "${INTERSHEET_REFS}" (at 370.1083 171.3706 0)
      (effects (font (size 1.27 1.27)) (justify left) hide)
    )
  )
  (global_label "CSI1_CLK_N" (shape input) (at 104.14 160.02 0) (fields_autoplaced)
    (effects (font (size 1.27 1.27)) (justify left))
    (property "Intersheetrefs" "${INTERSHEET_REFS}" (at 117.6807 159.9406 0)
      (effects (font (size 1.27 1.27)) (justify left) hide)
    )
  )
  (global_label "CSI1_D1_N" (shape input) (at 104.14 165.1 0) (fields_autoplaced)
    (effects (font (size 1.27 1.27)) (justify left))
    (property "Intersheetrefs" "${INTERSHEET_REFS}" (at 116.5921 165.0206 0)
      (effects (font (size 1.27 1.27)) (justify left) hide)
    )
  )
  (global_label "CSI1_D4_P" (shape input) (at 104.14 177.8 0) (fields_autoplaced)
    (effects (font (size 1.27 1.27)) (justify left))
    (property "Intersheetrefs" "${INTERSHEET_REFS}" (at 116.5317 177.7206 0)
      (effects (font (size 1.27 1.27)) (justify left) hide)
    )
  )
  (global_label "CH1_1V2" (shape input) (at 255.27 205.74 0) (fields_autoplaced)
    (effects (font (size 1.27 1.27)) (justify left))
    (property "Intersheetrefs" "${INTERSHEET_REFS}" (at 265.9683 205.6606 0)
      (effects (font (size 1.27 1.27)) (justify left) hide)
    )
  )
  (global_label "I2C1_SDA" (shape input) (at 104.14 190.5 0) (fields_autoplaced)
    (effects (font (size 1.27 1.27)) (justify left))
    (property "Intersheetrefs" "${INTERSHEET_REFS}" (at 115.3826 190.4206 0)
      (effects (font (size 1.27 1.27)) (justify left) hide)
    )
  )
  (global_label "CSI1_D1_P" (shape input) (at 104.14 162.56 0) (fields_autoplaced)
    (effects (font (size 1.27 1.27)) (justify left))
    (property "Intersheetrefs" "${INTERSHEET_REFS}" (at 116.5317 162.4806 0)
      (effects (font (size 1.27 1.27)) (justify left) hide)
    )
  )

  (symbol (lib_id "antmicropower:GND") (at 219.71 215.9 0) (unit 1)
    (in_bom yes) (on_board yes) (dnp no)
    (property "Reference" "#PWR0108" (at 219.71 222.25 0)
      (effects (font (size 1.27 1.27)) hide)
    )
    (property "Value" "GND" (at 221.615 218.44 0)
      (effects (font (size 1.27 1.27) (thickness 0.15)) (justify left bottom))
    )
    (property "Footprint" "" (at 219.71 215.9 0)
      (effects (font (size 1.27 1.27) (thickness 0.15)) (justify left bottom) hide)
    )
    (property "Datasheet" "" (at 219.71 215.9 0)
      (effects (font (size 1.27 1.27) (thickness 0.15)) (justify left bottom) hide)
    )
    (property "Author" "Antmicro" (at 228.6 223.52 0)
      (effects (font (size 1.27 1.27) (thickness 0.15)) (justify left bottom) hide)
    )
    (property "License" "Apache-2.0" (at 228.6 226.06 0)
      (effects (font (size 1.27 1.27) (thickness 0.15)) (justify left bottom) hide)
    )
    (pin "1")
    (instances
      (project "antmicro-hdmi-mipi-bridge-hw"
        (path ""
          (reference "#PWR0108") (unit 1)
        )
      )
    )
  )

  (symbol (lib_id "antmicropower:GND") (at 114.3 85.09 0) (unit 1)
    (in_bom yes) (on_board yes) (dnp no)
    (property "Reference" "#PWR0143" (at 114.3 91.44 0)
      (effects (font (size 1.27 1.27)) hide)
    )
    (property "Value" "GND" (at 112.395 89.535 0)
      (effects (font (size 1.27 1.27) (thickness 0.15)) (justify left bottom))
    )
    (property "Footprint" "" (at 114.3 85.09 0)
      (effects (font (size 1.27 1.27) (thickness 0.15)) (justify left bottom) hide)
    )
    (property "Datasheet" "" (at 114.3 85.09 0)
      (effects (font (size 1.27 1.27) (thickness 0.15)) (justify left bottom) hide)
    )
    (property "Author" "Antmicro" (at 123.19 92.71 0)
      (effects (font (size 1.27 1.27) (thickness 0.15)) (justify left bottom) hide)
    )
    (property "License" "Apache-2.0" (at 123.19 95.25 0)
      (effects (font (size 1.27 1.27) (thickness 0.15)) (justify left bottom) hide)
    )
    (pin "1")
    (instances
      (project "antmicro-hdmi-mipi-bridge-hw"
        (path ""
          (reference "#PWR0143") (unit 1)
        )
      )
    )
  )

  (symbol (lib_id "antmicropower:GND") (at 353.06 175.26 0) (unit 1)
    (in_bom yes) (on_board yes) (dnp no)
    (property "Reference" "#PWR0127" (at 353.06 181.61 0)
      (effects (font (size 1.27 1.27)) hide)
    )
    (property "Value" "GND" (at 351.155 179.705 0)
      (effects (font (size 1.27 1.27) (thickness 0.15)) (justify left bottom))
    )
    (property "Footprint" "" (at 353.06 175.26 0)
      (effects (font (size 1.27 1.27) (thickness 0.15)) (justify left bottom) hide)
    )
    (property "Datasheet" "" (at 353.06 175.26 0)
      (effects (font (size 1.27 1.27) (thickness 0.15)) (justify left bottom) hide)
    )
    (property "Author" "Antmicro" (at 361.95 182.88 0)
      (effects (font (size 1.27 1.27) (thickness 0.15)) (justify left bottom) hide)
    )
    (property "License" "Apache-2.0" (at 361.95 185.42 0)
      (effects (font (size 1.27 1.27) (thickness 0.15)) (justify left bottom) hide)
    )
    (pin "1")
    (instances
      (project "antmicro-hdmi-mipi-bridge-hw"
        (path ""
          (reference "#PWR0127") (unit 1)
        )
      )
    )
  )

  (symbol (lib_id "antmicroCapacitors0603:C_4u7_0603") (at 231.14 228.6 90) (unit 1)
    (in_bom yes) (on_board yes) (dnp no) (fields_autoplaced)
    (property "Reference" "C10" (at 233.68 224.7836 90)
      (effects (font (size 1.524 1.524)) (justify right))
    )
    (property "Value" "C_4u7_0603" (at 241.3 208.28 0)
      (effects (font (size 1.27 1.27) (thickness 0.15)) (justify left bottom) hide)
    )
    (property "Footprint" "antmicro-footprints:C_0603_1608Metric" (at 243.84 208.28 0)
      (effects (font (size 1.27 1.27) (thickness 0.15)) (justify left bottom) hide)
    )
    (property "Datasheet" "https://product.tdk.com/en/search/capacitor/ceramic/mlcc/info?part_no=C1608X5R1V475M080AC" (at 246.38 208.28 0)
      (effects (font (size 1.27 1.27) (thickness 0.15)) (justify left bottom) hide)
    )
    (property "Manufacturer" "TDK" (at 251.46 208.28 0)
      (effects (font (size 1.27 1.27) (thickness 0.15)) (justify left bottom) hide)
    )
    (property "MPN" "C1608X5R1V475M080AC" (at 248.92 208.28 0)
      (effects (font (size 1.27 1.27) (thickness 0.15)) (justify left bottom) hide)
    )
    (property "Val" "4u7" (at 233.68 227.3236 90)
      (effects (font (size 1.27 1.27) (thickness 0.15)) (justify right))
    )
    (property "License" "Apache-2.0" (at 254 208.28 0)
      (effects (font (size 1.27 1.27) (thickness 0.15)) (justify left bottom) hide)
    )
    (property "Author" "Antmicro" (at 256.54 208.28 0)
      (effects (font (size 1.27 1.27) (thickness 0.15)) (justify left bottom) hide)
    )
    (property "Voltage" "" (at 259.08 208.28 0)
      (effects (font (size 1.27 1.27)) (justify left bottom) hide)
    )
    (property "Dielectric" "" (at 261.62 208.28 0)
      (effects (font (size 1.27 1.27)) (justify left bottom) hide)
    )
    (property "Public" "False" (at 264.16 208.28 0)
      (effects (font (size 1.27 1.27)) (justify left bottom) hide)
    )
    (pin "1")
    (pin "2")
    (instances
      (project "antmicro-hdmi-mipi-bridge-hw"
        (path ""
          (reference "C10") (unit 1)
        )
      )
    )
  )

  (symbol (lib_id "antmicroCapacitors0402:C_470p_0402") (at 219.71 241.3 270) (unit 1)
    (in_bom yes) (on_board yes) (dnp no)
    (property "Reference" "C7" (at 217.17 243.205 90)
      (effects (font (size 1.524 1.524)) (justify right))
    )
    (property "Value" "C_470p_0402" (at 209.55 261.62 0)
      (effects (font (size 1.27 1.27) (thickness 0.15)) (justify left bottom) hide)
    )
    (property "Footprint" "antmicro-footprints:C_0402_1005Metric" (at 207.01 261.62 0)
      (effects (font (size 1.27 1.27) (thickness 0.15)) (justify left bottom) hide)
    )
    (property "Datasheet" "https://www.passivecomponent.com/wp-content/uploads/datasheet/WTC_MLCC_General_Purpose.pdf" (at 204.47 261.62 0)
      (effects (font (size 1.27 1.27) (thickness 0.15)) (justify left bottom) hide)
    )
    (property "Manufacturer" "Walsin" (at 199.39 261.62 0)
      (effects (font (size 1.27 1.27) (thickness 0.15)) (justify left bottom) hide)
    )
    (property "MPN" "0402B471K250CT" (at 201.93 261.62 0)
      (effects (font (size 1.27 1.27) (thickness 0.15)) (justify left bottom) hide)
    )
    (property "Val" "470p" (at 213.995 245.745 90)
      (effects (font (size 1.27 1.27) (thickness 0.15)) (justify left bottom))
    )
    (property "License" "Apache-2.0" (at 196.85 261.62 0)
      (effects (font (size 1.27 1.27) (thickness 0.15)) (justify left bottom) hide)
    )
    (property "Author" "Antmicro" (at 194.31 261.62 0)
      (effects (font (size 1.27 1.27) (thickness 0.15)) (justify left bottom) hide)
    )
    (property "Voltage" "" (at 191.77 261.62 0)
      (effects (font (size 1.27 1.27)) (justify left bottom) hide)
    )
    (property "Dielectric" "" (at 189.23 261.62 0)
      (effects (font (size 1.27 1.27)) (justify left bottom) hide)
    )
    (property "Public" "False" (at 186.69 261.62 0)
      (effects (font (size 1.27 1.27)) (justify left bottom) hide)
    )
    (pin "1")
    (pin "2")
    (instances
      (project "antmicro-hdmi-mipi-bridge-hw"
        (path ""
          (reference "C7") (unit 1)
        )
      )
    )
  )

  (symbol (lib_id "antmicroResistors0402:R_10k_0402") (at 360.68 92.71 90) (unit 1)
    (in_bom yes) (on_board yes) (dnp no)
    (property "Reference" "R11" (at 363.22 91.44 90)
      (effects (font (size 1.524 1.524)) (justify right))
    )
    (property "Value" "R_10k_0402" (at 373.38 72.39 0)
      (effects (font (size 1.27 1.27) (thickness 0.15)) (justify left bottom) hide)
    )
    (property "Footprint" "antmicro-footprints:R_0402_1005Metric" (at 375.92 72.39 0)
      (effects (font (size 1.27 1.27) (thickness 0.15)) (justify left bottom) hide)
    )
    (property "Datasheet" "https://www.bourns.com/docs/product-datasheets/cr.pdf" (at 378.46 72.39 0)
      (effects (font (size 1.27 1.27) (thickness 0.15)) (justify left bottom) hide)
    )
    (property "Manufacturer" "Bourns" (at 383.54 72.39 0)
      (effects (font (size 1.27 1.27) (thickness 0.15)) (justify left bottom) hide)
    )
    (property "MPN" "CR0402-FX-1002GLF" (at 381 72.39 0)
      (effects (font (size 1.27 1.27) (thickness 0.15)) (justify left bottom) hide)
    )
    (property "Val" "10k" (at 367.03 92.71 90)
      (effects (font (size 1.27 1.27) (thickness 0.15)) (justify left bottom))
    )
    (property "License" "Apache-2.0" (at 386.08 72.39 0)
      (effects (font (size 1.27 1.27) (thickness 0.15)) (justify left bottom) hide)
    )
    (property "Author" "Antmicro" (at 388.62 72.39 0)
      (effects (font (size 1.27 1.27) (thickness 0.15)) (justify left bottom) hide)
    )
    (property "Tolerance" "1%" (at 370.84 72.39 0)
      (effects (font (size 1.27 1.27)) (justify left bottom) hide)
    )
    (property "Public" "False" (at 391.16 72.39 0)
      (effects (font (size 1.27 1.27)) (justify left bottom) hide)
    )
    (pin "1")
    (pin "2")
    (instances
      (project "antmicro-hdmi-mipi-bridge-hw"
        (path ""
          (reference "R11") (unit 1)
        )
      )
    )
  )

  (symbol (lib_id "antmicroCapacitors0603:C_10u_0603") (at 358.14 180.34 90) (unit 1)
    (in_bom yes) (on_board yes) (dnp no)
    (property "Reference" "C19" (at 366.395 177.165 90)
      (effects (font (size 1.524 1.524)) (justify left))
    )
    (property "Value" "C_10u_0603" (at 368.3 160.02 0)
      (effects (font (size 1.27 1.27) (thickness 0.15)) (justify left bottom) hide)
    )
    (property "Footprint" "antmicro-footprints:C_0603_1608Metric" (at 370.84 160.02 0)
      (effects (font (size 1.27 1.27) (thickness 0.15)) (justify left bottom) hide)
    )
    (property "Datasheet" "https://www.murata.com/products/productdetail?partno=GRM188R61A106KE69%23" (at 373.38 160.02 0)
      (effects (font (size 1.27 1.27) (thickness 0.15)) (justify left bottom) hide)
    )
    (property "Manufacturer" "Murata" (at 378.46 160.02 0)
      (effects (font (size 1.27 1.27) (thickness 0.15)) (justify left bottom) hide)
    )
    (property "MPN" "GRM188R61A106KE69D" (at 375.92 160.02 0)
      (effects (font (size 1.27 1.27) (thickness 0.15)) (justify left bottom) hide)
    )
    (property "Val" "10u" (at 365.76 179.07 90)
      (effects (font (size 1.27 1.27) (thickness 0.15)) (justify left bottom))
    )
    (property "License" "Apache-2.0" (at 381 160.02 0)
      (effects (font (size 1.27 1.27) (thickness 0.15)) (justify left bottom) hide)
    )
    (property "Author" "Antmicro" (at 383.54 160.02 0)
      (effects (font (size 1.27 1.27) (thickness 0.15)) (justify left bottom) hide)
    )
    (property "Voltage" "" (at 386.08 160.02 0)
      (effects (font (size 1.27 1.27)) (justify left bottom) hide)
    )
    (property "Dielectric" "template_dielectric" (at 388.62 160.02 0)
      (effects (font (size 1.27 1.27)) (justify left bottom) hide)
    )
    (property "Public" "False" (at 391.16 160.02 0)
      (effects (font (size 1.27 1.27)) (justify left bottom) hide)
    )
    (pin "1")
    (pin "2")
    (instances
      (project "antmicro-hdmi-mipi-bridge-hw"
        (path ""
          (reference "C19") (unit 1)
        )
      )
    )
  )

  (symbol (lib_id "antmicroResistors0402:R_10k_0402") (at 318.77 92.71 270) (mirror x) (unit 1)
    (in_bom yes) (on_board yes) (dnp no)
    (property "Reference" "R9" (at 316.23 90.805 90)
      (effects (font (size 1.524 1.524)) (justify right))
    )
    (property "Value" "R_10k_0402" (at 306.07 72.39 0)
      (effects (font (size 1.27 1.27) (thickness 0.15)) (justify left bottom) hide)
    )
    (property "Footprint" "antmicro-footprints:R_0402_1005Metric" (at 303.53 72.39 0)
      (effects (font (size 1.27 1.27) (thickness 0.15)) (justify left bottom) hide)
    )
    (property "Datasheet" "https://www.bourns.com/docs/product-datasheets/cr.pdf" (at 300.99 72.39 0)
      (effects (font (size 1.27 1.27) (thickness 0.15)) (justify left bottom) hide)
    )
    (property "Manufacturer" "Bourns" (at 295.91 72.39 0)
      (effects (font (size 1.27 1.27) (thickness 0.15)) (justify left bottom) hide)
    )
    (property "MPN" "CR0402-FX-1002GLF" (at 298.45 72.39 0)
      (effects (font (size 1.27 1.27) (thickness 0.15)) (justify left bottom) hide)
    )
    (property "Val" "10k" (at 313.055 92.71 90)
      (effects (font (size 1.27 1.27) (thickness 0.15)) (justify left bottom))
    )
    (property "License" "Apache-2.0" (at 293.37 72.39 0)
      (effects (font (size 1.27 1.27) (thickness 0.15)) (justify left bottom) hide)
    )
    (property "Author" "Antmicro" (at 290.83 72.39 0)
      (effects (font (size 1.27 1.27) (thickness 0.15)) (justify left bottom) hide)
    )
    (property "Tolerance" "1%" (at 308.61 72.39 0)
      (effects (font (size 1.27 1.27)) (justify left bottom) hide)
    )
    (property "Public" "False" (at 288.29 72.39 0)
      (effects (font (size 1.27 1.27)) (justify left bottom) hide)
    )
    (pin "1")
    (pin "2")
    (instances
      (project "antmicro-hdmi-mipi-bridge-hw"
        (path ""
          (reference "R9") (unit 1)
        )
      )
    )
  )

  (symbol (lib_id "antmicroResistors0603:R_0R_0603") (at 189.865 218.44 0) (unit 1)
    (in_bom yes) (on_board yes) (dnp no)
    (property "Reference" "R5" (at 192.405 220.98 0)
      (effects (font (size 1.524 1.524)))
    )
    (property "Value" "R_0R_0603" (at 210.185 231.14 0)
      (effects (font (size 1.27 1.27) (thickness 0.15)) (justify left bottom) hide)
    )
    (property "Footprint" "antmicro-footprints:R_0603_1608Metric" (at 210.185 233.68 0)
      (effects (font (size 1.27 1.27) (thickness 0.15)) (justify left bottom) hide)
    )
    (property "Datasheet" "https://www.bourns.com/docs/product-datasheets/cr.pdf?sfvrsn=574d41f6_14" (at 210.185 236.22 0)
      (effects (font (size 1.27 1.27) (thickness 0.15)) (justify left bottom) hide)
    )
    (property "Manufacturer" "Bourns" (at 210.185 241.3 0)
      (effects (font (size 1.27 1.27) (thickness 0.15)) (justify left bottom) hide)
    )
    (property "MPN" "CR0603-J/-000ELF" (at 210.185 238.76 0)
      (effects (font (size 1.27 1.27) (thickness 0.15)) (justify left bottom) hide)
    )
    (property "Val" "0R" (at 191.135 224.155 0)
      (effects (font (size 1.27 1.27) (thickness 0.15)) (justify left bottom))
    )
    (property "License" "Apache-2.0" (at 210.185 243.84 0)
      (effects (font (size 1.27 1.27) (thickness 0.15)) (justify left bottom) hide)
    )
    (property "Author" "Antmicro" (at 210.185 246.38 0)
      (effects (font (size 1.27 1.27) (thickness 0.15)) (justify left bottom) hide)
    )
    (property "Tolerance" "~" (at 210.185 228.6 0)
      (effects (font (size 1.27 1.27)) (justify left bottom) hide)
    )
    (property "Current" "1A" (at 210.185 248.92 0)
      (effects (font (size 1.27 1.27) (thickness 0.15)) (justify left bottom) hide)
    )
    (property "Public" "False" (at 210.185 248.92 0)
      (effects (font (size 1.27 1.27)) (justify left bottom) hide)
    )
    (pin "1")
    (pin "2")
    (instances
      (project "antmicro-hdmi-mipi-bridge-hw"
        (path ""
          (reference "R5") (unit 1)
        )
      )
    )
  )

  (symbol (lib_id "antmicroResistors0402:R_10k_0402") (at 369.57 92.71 90) (unit 1)
    (in_bom yes) (on_board yes) (dnp no)
    (property "Reference" "R12" (at 372.11 91.44 90)
      (effects (font (size 1.524 1.524)) (justify right))
    )
    (property "Value" "R_10k_0402" (at 382.27 72.39 0)
      (effects (font (size 1.27 1.27) (thickness 0.15)) (justify left bottom) hide)
    )
    (property "Footprint" "antmicro-footprints:R_0402_1005Metric" (at 384.81 72.39 0)
      (effects (font (size 1.27 1.27) (thickness 0.15)) (justify left bottom) hide)
    )
    (property "Datasheet" "https://www.bourns.com/docs/product-datasheets/cr.pdf" (at 387.35 72.39 0)
      (effects (font (size 1.27 1.27) (thickness 0.15)) (justify left bottom) hide)
    )
    (property "Manufacturer" "Bourns" (at 392.43 72.39 0)
      (effects (font (size 1.27 1.27) (thickness 0.15)) (justify left bottom) hide)
    )
    (property "MPN" "CR0402-FX-1002GLF" (at 389.89 72.39 0)
      (effects (font (size 1.27 1.27) (thickness 0.15)) (justify left bottom) hide)
    )
    (property "Val" "10k" (at 376.555 92.71 90)
      (effects (font (size 1.27 1.27) (thickness 0.15)) (justify left bottom))
    )
    (property "License" "Apache-2.0" (at 394.97 72.39 0)
      (effects (font (size 1.27 1.27) (thickness 0.15)) (justify left bottom) hide)
    )
    (property "Author" "Antmicro" (at 397.51 72.39 0)
      (effects (font (size 1.27 1.27) (thickness 0.15)) (justify left bottom) hide)
    )
    (property "Tolerance" "1%" (at 379.73 72.39 0)
      (effects (font (size 1.27 1.27)) (justify left bottom) hide)
    )
    (property "Public" "False" (at 400.05 72.39 0)
      (effects (font (size 1.27 1.27)) (justify left bottom) hide)
    )
    (pin "1")
    (pin "2")
    (instances
      (project "antmicro-hdmi-mipi-bridge-hw"
        (path ""
          (reference "R12") (unit 1)
        )
      )
    )
  )

  (symbol (lib_id "antmicroCapacitors0402:C_100n_0402") (at 85.09 259.08 90) (unit 1)
    (in_bom yes) (on_board yes) (dnp no)
    (property "Reference" "C1" (at 81.915 255.27 90)
      (effects (font (size 1.524 1.524)) (justify left))
    )
    (property "Value" "C_100n_0402" (at 95.25 238.76 0)
      (effects (font (size 1.27 1.27) (thickness 0.15)) (justify left bottom) hide)
    )
    (property "Footprint" "antmicro-footprints:C_0402_1005Metric" (at 97.79 238.76 0)
      (effects (font (size 1.27 1.27) (thickness 0.15)) (justify left bottom) hide)
    )
    (property "Datasheet" "https://www.murata.com/products/productdetail?partno=GRM155R61H104KE14%23" (at 100.33 238.76 0)
      (effects (font (size 1.27 1.27) (thickness 0.15)) (justify left bottom) hide)
    )
    (property "Manufacturer" "Murata" (at 105.41 238.76 0)
      (effects (font (size 1.27 1.27) (thickness 0.15)) (justify left bottom) hide)
    )
    (property "MPN" "GRM155R61H104KE14D" (at 102.87 238.76 0)
      (effects (font (size 1.27 1.27) (thickness 0.15)) (justify left bottom) hide)
    )
    (property "Val" "100n" (at 83.185 257.81 90)
      (effects (font (size 1.27 1.27) (thickness 0.15)) (justify left bottom))
    )
    (property "License" "Apache-2.0" (at 107.95 238.76 0)
      (effects (font (size 1.27 1.27) (thickness 0.15)) (justify left bottom) hide)
    )
    (property "Author" "Antmicro" (at 110.49 238.76 0)
      (effects (font (size 1.27 1.27) (thickness 0.15)) (justify left bottom) hide)
    )
    (property "Voltage" "50V" (at 113.03 238.76 0)
      (effects (font (size 1.27 1.27)) (justify left bottom) hide)
    )
    (property "Dielectric" "X5R" (at 115.57 238.76 0)
      (effects (font (size 1.27 1.27)) (justify left bottom) hide)
    )
    (property "Public" "False" (at 118.11 238.76 0)
      (effects (font (size 1.27 1.27)) (justify left bottom) hide)
    )
    (pin "1")
    (pin "2")
    (instances
      (project "antmicro-hdmi-mipi-bridge-hw"
        (path ""
          (reference "C1") (unit 1)
        )
      )
    )
  )

  (symbol (lib_id "antmicroCapacitors0402:C_47p_0402") (at 302.26 45.72 90) (unit 1)
    (in_bom yes) (on_board yes) (dnp no)
    (property "Reference" "C13" (at 308.61 41.275 90)
      (effects (font (size 1.524 1.524)) (justify left))
    )
    (property "Value" "C_47p_0402" (at 312.42 25.4 0)
      (effects (font (size 1.27 1.27) (thickness 0.15)) (justify left bottom) hide)
    )
    (property "Footprint" "antmicro-footprints:C_0402_1005Metric" (at 314.96 25.4 0)
      (effects (font (size 1.27 1.27) (thickness 0.15)) (justify left bottom) hide)
    )
    (property "Datasheet" "https://www.kemet.com/en/us/capacitors/product/C0402C470J5GACTU.html" (at 317.5 25.4 0)
      (effects (font (size 1.27 1.27) (thickness 0.15)) (justify left bottom) hide)
    )
    (property "Manufacturer" "KEMET" (at 322.58 25.4 0)
      (effects (font (size 1.27 1.27) (thickness 0.15)) (justify left bottom) hide)
    )
    (property "MPN" "C0402C470J5GACTU" (at 320.04 25.4 0)
      (effects (font (size 1.27 1.27) (thickness 0.15)) (justify left bottom) hide)
    )
    (property "Val" "47p" (at 308.61 42.545 90)
      (effects (font (size 1.27 1.27) (thickness 0.15)) (justify left bottom))
    )
    (property "License" "Apache-2.0" (at 325.12 25.4 0)
      (effects (font (size 1.27 1.27) (thickness 0.15)) (justify left bottom) hide)
    )
    (property "Author" "Antmicro" (at 327.66 25.4 0)
      (effects (font (size 1.27 1.27) (thickness 0.15)) (justify left bottom) hide)
    )
    (property "Voltage" "" (at 330.2 25.4 0)
      (effects (font (size 1.27 1.27)) (justify left bottom) hide)
    )
    (property "Dielectric" "C0G" (at 332.74 25.4 0)
      (effects (font (size 1.27 1.27)) (justify left bottom) hide)
    )
    (property "Public" "False" (at 335.28 25.4 0)
      (effects (font (size 1.27 1.27)) (justify left bottom) hide)
    )
    (pin "1")
    (pin "2")
    (instances
      (project "antmicro-hdmi-mipi-bridge-hw"
        (path ""
          (reference "C13") (unit 1)
        )
      )
    )
  )

  (symbol (lib_id "antmicroCapacitors0603:C_4u7_0603") (at 231.14 198.12 90) (unit 1)
    (in_bom yes) (on_board yes) (dnp no) (fields_autoplaced)
    (property "Reference" "C8" (at 233.68 194.3036 90)
      (effects (font (size 1.524 1.524)) (justify right))
    )
    (property "Value" "C_4u7_0603" (at 241.3 177.8 0)
      (effects (font (size 1.27 1.27) (thickness 0.15)) (justify left bottom) hide)
    )
    (property "Footprint" "antmicro-footprints:C_0603_1608Metric" (at 243.84 177.8 0)
      (effects (font (size 1.27 1.27) (thickness 0.15)) (justify left bottom) hide)
    )
    (property "Datasheet" "https://product.tdk.com/en/search/capacitor/ceramic/mlcc/info?part_no=C1608X5R1V475M080AC" (at 246.38 177.8 0)
      (effects (font (size 1.27 1.27) (thickness 0.15)) (justify left bottom) hide)
    )
    (property "Manufacturer" "TDK" (at 251.46 177.8 0)
      (effects (font (size 1.27 1.27) (thickness 0.15)) (justify left bottom) hide)
    )
    (property "MPN" "C1608X5R1V475M080AC" (at 248.92 177.8 0)
      (effects (font (size 1.27 1.27) (thickness 0.15)) (justify left bottom) hide)
    )
    (property "Val" "4u7" (at 233.68 196.8436 90)
      (effects (font (size 1.27 1.27) (thickness 0.15)) (justify right))
    )
    (property "License" "Apache-2.0" (at 254 177.8 0)
      (effects (font (size 1.27 1.27) (thickness 0.15)) (justify left bottom) hide)
    )
    (property "Author" "Antmicro" (at 256.54 177.8 0)
      (effects (font (size 1.27 1.27) (thickness 0.15)) (justify left bottom) hide)
    )
    (property "Voltage" "" (at 259.08 177.8 0)
      (effects (font (size 1.27 1.27)) (justify left bottom) hide)
    )
    (property "Dielectric" "" (at 261.62 177.8 0)
      (effects (font (size 1.27 1.27)) (justify left bottom) hide)
    )
    (property "Public" "False" (at 264.16 177.8 0)
      (effects (font (size 1.27 1.27)) (justify left bottom) hide)
    )
    (pin "1")
    (pin "2")
    (instances
      (project "antmicro-hdmi-mipi-bridge-hw"
        (path ""
          (reference "C8") (unit 1)
        )
      )
    )
  )

  (symbol (lib_id "antmicropower:GND") (at 182.88 231.14 0) (unit 1)
    (in_bom yes) (on_board yes) (dnp no)
    (property "Reference" "#PWR0155" (at 182.88 237.49 0)
      (effects (font (size 1.27 1.27)) hide)
    )
    (property "Value" "GND" (at 180.975 235.585 0)
      (effects (font (size 1.27 1.27) (thickness 0.15)) (justify left bottom))
    )
    (property "Footprint" "" (at 182.88 231.14 0)
      (effects (font (size 1.27 1.27) (thickness 0.15)) (justify left bottom) hide)
    )
    (property "Datasheet" "" (at 182.88 231.14 0)
      (effects (font (size 1.27 1.27) (thickness 0.15)) (justify left bottom) hide)
    )
    (property "Author" "Antmicro" (at 191.77 238.76 0)
      (effects (font (size 1.27 1.27) (thickness 0.15)) (justify left bottom) hide)
    )
    (property "License" "Apache-2.0" (at 191.77 241.3 0)
      (effects (font (size 1.27 1.27) (thickness 0.15)) (justify left bottom) hide)
    )
    (pin "1")
    (instances
      (project "antmicro-hdmi-mipi-bridge-hw"
        (path ""
          (reference "#PWR0155") (unit 1)
        )
      )
    )
  )

  (symbol (lib_id "antmicropower:GND") (at 219.71 154.94 0) (unit 1)
    (in_bom yes) (on_board yes) (dnp no)
    (property "Reference" "#PWR0154" (at 219.71 161.29 0)
      (effects (font (size 1.27 1.27)) hide)
    )
    (property "Value" "GND" (at 221.615 157.48 0)
      (effects (font (size 1.27 1.27) (thickness 0.15)) (justify left bottom))
    )
    (property "Footprint" "" (at 219.71 154.94 0)
      (effects (font (size 1.27 1.27) (thickness 0.15)) (justify left bottom) hide)
    )
    (property "Datasheet" "" (at 219.71 154.94 0)
      (effects (font (size 1.27 1.27) (thickness 0.15)) (justify left bottom) hide)
    )
    (property "Author" "Antmicro" (at 228.6 162.56 0)
      (effects (font (size 1.27 1.27) (thickness 0.15)) (justify left bottom) hide)
    )
    (property "License" "Apache-2.0" (at 228.6 165.1 0)
      (effects (font (size 1.27 1.27) (thickness 0.15)) (justify left bottom) hide)
    )
    (pin "1")
    (instances
      (project "antmicro-hdmi-mipi-bridge-hw"
        (path ""
          (reference "#PWR0154") (unit 1)
        )
      )
    )
  )

  (symbol (lib_id "antmicroTVSDiodes:TPD8S009DSMR") (at 166.37 49.53 0) (unit 1)
    (in_bom yes) (on_board yes) (dnp no)
    (property "Reference" "U2" (at 174.625 43.815 0)
      (effects (font (size 1.27 1.27)))
    )
    (property "Value" "TPD8S009DSMR" (at 196.85 62.23 0)
      (effects (font (size 1.27 1.27) (thickness 0.15)) (justify left bottom) hide)
    )
    (property "Footprint" "antmicro-footprints:R-PDSO-N15" (at 196.85 57.15 0)
      (effects (font (size 1.27 1.27) (thickness 0.15)) (justify left bottom) hide)
    )
    (property "Datasheet" "https://www.ti.com/lit/ds/symlink/tpd8s009.pdf?ts=1679406571326&ref_url=https%253A%252F%252Fwww.ti.com%252Fproduct%252FTPD8S009%252Fpart-details%252FTPD8S009DSMR" (at 196.85 59.69 0)
      (effects (font (size 1.27 1.27) (thickness 0.15)) (justify left bottom) hide)
    )
    (property "MPN" "TPD8S009DSMR" (at 167.005 46.355 0)
      (effects (font (size 1.27 1.27) (thickness 0.15)) (justify left bottom))
    )
    (property "Manufacturer" "Texas Instruments" (at 196.85 64.77 0)
      (effects (font (size 1.27 1.27) (thickness 0.15)) (justify left bottom) hide)
    )
    (property "Author" "Antmicro" (at 196.85 67.31 0)
      (effects (font (size 1.27 1.27) (thickness 0.15)) (justify left bottom) hide)
    )
    (property "License" "Apache-2.0" (at 196.85 69.85 0)
      (effects (font (size 1.27 1.27) (thickness 0.15)) (justify left bottom) hide)
    )
    (pin "1")
    (pin "10")
    (pin "11")
    (pin "12")
    (pin "13")
    (pin "14")
    (pin "15")
    (pin "2")
    (pin "3")
    (pin "4")
    (pin "5")
    (pin "6")
    (pin "7")
    (pin "8")
    (pin "9")
    (pin "8")
    (instances
      (project "antmicro-hdmi-mipi-bridge-hw"
        (path ""
          (reference "U2") (unit 1)
        )
      )
    )
  )

  (symbol (lib_id "antmicroFerriteBeadsandChips:FB_1kZ_0.8A_WE-CBF_0805") (at 245.11 238.76 0) (unit 1)
    (in_bom yes) (on_board yes) (dnp no)
    (property "Reference" "FB5" (at 247.65 233.68 0)
      (effects (font (size 1.524 1.524)))
    )
    (property "Value" "FB_1kZ_0.8A_WE-CBF_0805" (at 260.35 246.888 0)
      (effects (font (size 1.27 1.27) (thickness 0.15)) (justify left bottom) hide)
    )
    (property "Footprint" "antmicro-footprints:FB_0805_2012Metric" (at 260.35 249.428 0)
      (effects (font (size 1.27 1.27) (thickness 0.15)) (justify left bottom) hide)
    )
    (property "Datasheet" "https://www.we-online.com/components/products/datasheet/742792096.pdf" (at 260.35 251.968 0)
      (effects (font (size 1.27 1.27) (thickness 0.15)) (justify left bottom) hide)
    )
    (property "MPN" "742792096" (at 260.35 241.3 0)
      (effects (font (size 1.27 1.27) (thickness 0.15)) (justify left bottom) hide)
    )
    (property "Manufacturer" "Würth Elektronik" (at 260.35 254.508 0)
      (effects (font (size 1.27 1.27) (thickness 0.15)) (justify left bottom) hide)
    )
    (property "Author" "Antmicro" (at 260.35 257.048 0)
      (effects (font (size 1.27 1.27) (thickness 0.15)) (justify left bottom) hide)
    )
    (property "License" "Apache-2.0" (at 260.35 259.588 0)
      (effects (font (size 1.27 1.27) (thickness 0.15)) (justify left bottom) hide)
    )
    (property "Val" "1kZ/0.8A" (at 243.84 236.22 0)
      (effects (font (size 1.27 1.27)) (justify left bottom))
    )
    (property "Current" "" (at 265.43 261.62 0)
      (effects (font (size 1.27 1.27) (thickness 0.15)) (justify left bottom) hide)
    )
    (property "Public" "False" (at 265.43 254 0)
      (effects (font (size 1.27 1.27)) (justify left bottom) hide)
    )
    (pin "1")
    (pin "2")
    (instances
      (project "antmicro-hdmi-mipi-bridge-hw"
        (path ""
          (reference "FB5") (unit 1)
        )
      )
    )
  )

  (symbol (lib_id "antmicropower:GND") (at 93.98 261.62 0) (unit 1)
    (in_bom yes) (on_board yes) (dnp no)
    (property "Reference" "#PWR0137" (at 93.98 267.97 0)
      (effects (font (size 1.27 1.27)) hide)
    )
    (property "Value" "GND" (at 92.075 266.7 0)
      (effects (font (size 1.27 1.27) (thickness 0.15)) (justify left bottom))
    )
    (property "Footprint" "" (at 93.98 261.62 0)
      (effects (font (size 1.27 1.27) (thickness 0.15)) (justify left bottom) hide)
    )
    (property "Datasheet" "" (at 93.98 261.62 0)
      (effects (font (size 1.27 1.27) (thickness 0.15)) (justify left bottom) hide)
    )
    (property "Author" "Antmicro" (at 102.87 269.24 0)
      (effects (font (size 1.27 1.27) (thickness 0.15)) (justify left bottom) hide)
    )
    (property "License" "Apache-2.0" (at 102.87 271.78 0)
      (effects (font (size 1.27 1.27) (thickness 0.15)) (justify left bottom) hide)
    )
    (pin "1")
    (instances
      (project "antmicro-hdmi-mipi-bridge-hw"
        (path ""
          (reference "#PWR0137") (unit 1)
        )
      )
    )
  )

  (symbol (lib_id "antmicroPMICVoltageRegulatorsLinear:TLV73312PDBVT") (at 331.47 205.74 0) (unit 1)
    (in_bom yes) (on_board yes) (dnp no)
    (property "Reference" "IC2" (at 341.63 199.39 0)
      (effects (font (size 1.27 1.27)))
    )
    (property "Value" "TLV73312PDBVT" (at 334.645 202.565 0)
      (effects (font (size 1.27 1.27) (thickness 0.15)) (justify left bottom) hide)
    )
    (property "Footprint" "antmicro-footprints:SOT-23-5" (at 367.03 213.36 0)
      (effects (font (size 1.27 1.27) (thickness 0.15)) (justify left bottom) hide)
    )
    (property "Datasheet" "https://www.ti.com/lit/ds/symlink/tlv733p.pdf?HQS=dis-mous-null-mousermode-dsf-pf-null-wwe&ts=1676978230940&ref_url=https%253A%252F%252Fwww.mouser.com%252F" (at 367.03 215.9 0)
      (effects (font (size 1.27 1.27) (thickness 0.15)) (justify left bottom) hide)
    )
    (property "MPN" "TLV73312PDBVT" (at 334.01 202.565 0)
      (effects (font (size 1.27 1.27) (thickness 0.15)) (justify left bottom))
    )
    (property "Manufacturer" "Texas Instruments" (at 367.03 220.98 0)
      (effects (font (size 1.27 1.27) (thickness 0.15)) (justify left bottom) hide)
    )
    (property "Author" "Antmicro" (at 367.03 223.52 0)
      (effects (font (size 1.27 1.27) (thickness 0.15)) (justify left bottom) hide)
    )
    (property "License" "Apache-2.0" (at 367.03 226.06 0)
      (effects (font (size 1.27 1.27) (thickness 0.15)) (justify left bottom) hide)
    )
    (pin "1")
    (pin "2")
    (pin "3")
    (pin "4")
    (pin "5")
    (instances
      (project "antmicro-hdmi-mipi-bridge-hw"
        (path ""
          (reference "IC2") (unit 1)
        )
      )
    )
  )

  (symbol (lib_id "antmicroCapacitors0402:C_100n_0402") (at 219.71 182.88 90) (unit 1)
    (in_bom yes) (on_board yes) (dnp no) (fields_autoplaced)
    (property "Reference" "C30" (at 222.25 179.0636 90)
      (effects (font (size 1.524 1.524)) (justify right))
    )
    (property "Value" "C_100n_0402" (at 229.87 162.56 0)
      (effects (font (size 1.27 1.27) (thickness 0.15)) (justify left bottom) hide)
    )
    (property "Footprint" "antmicro-footprints:C_0402_1005Metric" (at 232.41 162.56 0)
      (effects (font (size 1.27 1.27) (thickness 0.15)) (justify left bottom) hide)
    )
    (property "Datasheet" "https://www.murata.com/products/productdetail?partno=GRM155R61H104KE14%23" (at 234.95 162.56 0)
      (effects (font (size 1.27 1.27) (thickness 0.15)) (justify left bottom) hide)
    )
    (property "Manufacturer" "Murata" (at 240.03 162.56 0)
      (effects (font (size 1.27 1.27) (thickness 0.15)) (justify left bottom) hide)
    )
    (property "MPN" "GRM155R61H104KE14D" (at 237.49 162.56 0)
      (effects (font (size 1.27 1.27) (thickness 0.15)) (justify left bottom) hide)
    )
    (property "Val" "100n" (at 222.25 181.6036 90)
      (effects (font (size 1.27 1.27) (thickness 0.15)) (justify right))
    )
    (property "License" "Apache-2.0" (at 242.57 162.56 0)
      (effects (font (size 1.27 1.27) (thickness 0.15)) (justify left bottom) hide)
    )
    (property "Author" "Antmicro" (at 245.11 162.56 0)
      (effects (font (size 1.27 1.27) (thickness 0.15)) (justify left bottom) hide)
    )
    (property "Voltage" "50V" (at 247.65 162.56 0)
      (effects (font (size 1.27 1.27)) (justify left bottom) hide)
    )
    (property "Dielectric" "X5R" (at 250.19 162.56 0)
      (effects (font (size 1.27 1.27)) (justify left bottom) hide)
    )
    (property "Public" "False" (at 252.73 162.56 0)
      (effects (font (size 1.27 1.27)) (justify left bottom) hide)
    )
    (pin "1")
    (pin "2")
    (instances
      (project "antmicro-hdmi-mipi-bridge-hw"
        (path ""
          (reference "C30") (unit 1)
        )
      )
    )
  )

  (symbol (lib_id "antmicroCapacitors0402:C_100n_0402") (at 307.34 86.36 90) (mirror x) (unit 1)
    (in_bom yes) (on_board yes) (dnp no)
    (property "Reference" "C14" (at 300.355 87.63 90)
      (effects (font (size 1.524 1.524)) (justify right))
    )
    (property "Value" "C_100n_0402" (at 317.5 106.68 0)
      (effects (font (size 1.27 1.27) (thickness 0.15)) (justify left bottom) hide)
    )
    (property "Footprint" "antmicro-footprints:C_0402_1005Metric" (at 320.04 106.68 0)
      (effects (font (size 1.27 1.27) (thickness 0.15)) (justify left bottom) hide)
    )
    (property "Datasheet" "https://www.murata.com/products/productdetail?partno=GRM155R61H104KE14%23" (at 322.58 106.68 0)
      (effects (font (size 1.27 1.27) (thickness 0.15)) (justify left bottom) hide)
    )
    (property "Manufacturer" "Murata" (at 327.66 106.68 0)
      (effects (font (size 1.27 1.27) (thickness 0.15)) (justify left bottom) hide)
    )
    (property "MPN" "GRM155R61H104KE14D" (at 325.12 106.68 0)
      (effects (font (size 1.27 1.27) (thickness 0.15)) (justify left bottom) hide)
    )
    (property "Val" "100n" (at 305.435 90.17 90)
      (effects (font (size 1.27 1.27) (thickness 0.15)) (justify left bottom))
    )
    (property "License" "Apache-2.0" (at 330.2 106.68 0)
      (effects (font (size 1.27 1.27) (thickness 0.15)) (justify left bottom) hide)
    )
    (property "Author" "Antmicro" (at 332.74 106.68 0)
      (effects (font (size 1.27 1.27) (thickness 0.15)) (justify left bottom) hide)
    )
    (property "Voltage" "50V" (at 335.28 106.68 0)
      (effects (font (size 1.27 1.27)) (justify left bottom) hide)
    )
    (property "Dielectric" "X5R" (at 337.82 106.68 0)
      (effects (font (size 1.27 1.27)) (justify left bottom) hide)
    )
    (property "Public" "False" (at 340.36 106.68 0)
      (effects (font (size 1.27 1.27)) (justify left bottom) hide)
    )
    (pin "1")
    (pin "2")
    (instances
      (project "antmicro-hdmi-mipi-bridge-hw"
        (path ""
          (reference "C14") (unit 1)
        )
      )
    )
  )

  (symbol (lib_id "antmicroCapacitors0402:C_470p_0402") (at 219.71 193.04 270) (unit 1)
    (in_bom yes) (on_board yes) (dnp no)
    (property "Reference" "C4" (at 217.17 194.945 90)
      (effects (font (size 1.524 1.524)) (justify right))
    )
    (property "Value" "C_470p_0402" (at 209.55 213.36 0)
      (effects (font (size 1.27 1.27) (thickness 0.15)) (justify left bottom) hide)
    )
    (property "Footprint" "antmicro-footprints:C_0402_1005Metric" (at 207.01 213.36 0)
      (effects (font (size 1.27 1.27) (thickness 0.15)) (justify left bottom) hide)
    )
    (property "Datasheet" "https://www.passivecomponent.com/wp-content/uploads/datasheet/WTC_MLCC_General_Purpose.pdf" (at 204.47 213.36 0)
      (effects (font (size 1.27 1.27) (thickness 0.15)) (justify left bottom) hide)
    )
    (property "Manufacturer" "Walsin" (at 199.39 213.36 0)
      (effects (font (size 1.27 1.27) (thickness 0.15)) (justify left bottom) hide)
    )
    (property "MPN" "0402B471K250CT" (at 201.93 213.36 0)
      (effects (font (size 1.27 1.27) (thickness 0.15)) (justify left bottom) hide)
    )
    (property "Val" "470p" (at 213.36 197.485 90)
      (effects (font (size 1.27 1.27) (thickness 0.15)) (justify left bottom))
    )
    (property "License" "Apache-2.0" (at 196.85 213.36 0)
      (effects (font (size 1.27 1.27) (thickness 0.15)) (justify left bottom) hide)
    )
    (property "Author" "Antmicro" (at 194.31 213.36 0)
      (effects (font (size 1.27 1.27) (thickness 0.15)) (justify left bottom) hide)
    )
    (property "Voltage" "" (at 191.77 213.36 0)
      (effects (font (size 1.27 1.27)) (justify left bottom) hide)
    )
    (property "Dielectric" "" (at 189.23 213.36 0)
      (effects (font (size 1.27 1.27)) (justify left bottom) hide)
    )
    (property "Public" "False" (at 186.69 213.36 0)
      (effects (font (size 1.27 1.27)) (justify left bottom) hide)
    )
    (pin "1")
    (pin "2")
    (instances
      (project "antmicro-hdmi-mipi-bridge-hw"
        (path ""
          (reference "C4") (unit 1)
        )
      )
    )
  )

  (symbol (lib_id "antmicropower:PWR_FLAG") (at 210.185 144.145 0) (unit 1)
    (in_bom yes) (on_board yes) (dnp no)
    (property "Reference" "#FLG0103" (at 210.185 142.24 0)
      (effects (font (size 1.27 1.27)) hide)
    )
    (property "Value" "PWR_FLAG" (at 210.185 140.335 0)
      (effects (font (size 1.27 1.27)))
    )
    (property "Footprint" "" (at 210.185 144.145 0)
      (effects (font (size 1.27 1.27)) hide)
    )
    (property "Datasheet" "" (at 210.185 144.145 0)
      (effects (font (size 1.27 1.27)) hide)
    )
    (pin "1")
    (instances
      (project "antmicro-hdmi-mipi-bridge-hw"
        (path ""
          (reference "#FLG0103") (unit 1)
        )
      )
    )
  )

  (symbol (lib_id "antmicroCapacitors0402:C_100n_0402") (at 316.23 45.72 90) (unit 1)
    (in_bom yes) (on_board yes) (dnp no)
    (property "Reference" "C15" (at 322.58 41.275 90)
      (effects (font (size 1.524 1.524)) (justify left))
    )
    (property "Value" "C_100n_0402" (at 326.39 25.4 0)
      (effects (font (size 1.27 1.27) (thickness 0.15)) (justify left bottom) hide)
    )
    (property "Footprint" "antmicro-footprints:C_0402_1005Metric" (at 328.93 25.4 0)
      (effects (font (size 1.27 1.27) (thickness 0.15)) (justify left bottom) hide)
    )
    (property "Datasheet" "https://www.murata.com/products/productdetail?partno=GRM155R61H104KE14%23" (at 331.47 25.4 0)
      (effects (font (size 1.27 1.27) (thickness 0.15)) (justify left bottom) hide)
    )
    (property "Manufacturer" "Murata" (at 336.55 25.4 0)
      (effects (font (size 1.27 1.27) (thickness 0.15)) (justify left bottom) hide)
    )
    (property "MPN" "GRM155R61H104KE14D" (at 334.01 25.4 0)
      (effects (font (size 1.27 1.27) (thickness 0.15)) (justify left bottom) hide)
    )
    (property "Val" "100n" (at 323.215 42.545 90)
      (effects (font (size 1.27 1.27) (thickness 0.15)) (justify left bottom))
    )
    (property "License" "Apache-2.0" (at 339.09 25.4 0)
      (effects (font (size 1.27 1.27) (thickness 0.15)) (justify left bottom) hide)
    )
    (property "Author" "Antmicro" (at 341.63 25.4 0)
      (effects (font (size 1.27 1.27) (thickness 0.15)) (justify left bottom) hide)
    )
    (property "Voltage" "50V" (at 344.17 25.4 0)
      (effects (font (size 1.27 1.27)) (justify left bottom) hide)
    )
    (property "Dielectric" "X5R" (at 346.71 25.4 0)
      (effects (font (size 1.27 1.27)) (justify left bottom) hide)
    )
    (property "Public" "False" (at 349.25 25.4 0)
      (effects (font (size 1.27 1.27)) (justify left bottom) hide)
    )
    (pin "1")
    (pin "2")
    (instances
      (project "antmicro-hdmi-mipi-bridge-hw"
        (path ""
          (reference "C15") (unit 1)
        )
      )
    )
  )

  (symbol (lib_id "antmicropower:GND") (at 358.14 218.44 0) (unit 1)
    (in_bom yes) (on_board yes) (dnp no)
    (property "Reference" "#PWR0130" (at 358.14 224.79 0)
      (effects (font (size 1.27 1.27)) hide)
    )
    (property "Value" "GND" (at 356.235 222.885 0)
      (effects (font (size 1.27 1.27) (thickness 0.15)) (justify left bottom))
    )
    (property "Footprint" "" (at 358.14 218.44 0)
      (effects (font (size 1.27 1.27) (thickness 0.15)) (justify left bottom) hide)
    )
    (property "Datasheet" "" (at 358.14 218.44 0)
      (effects (font (size 1.27 1.27) (thickness 0.15)) (justify left bottom) hide)
    )
    (property "Author" "Antmicro" (at 367.03 226.06 0)
      (effects (font (size 1.27 1.27) (thickness 0.15)) (justify left bottom) hide)
    )
    (property "License" "Apache-2.0" (at 367.03 228.6 0)
      (effects (font (size 1.27 1.27) (thickness 0.15)) (justify left bottom) hide)
    )
    (pin "1")
    (instances
      (project "antmicro-hdmi-mipi-bridge-hw"
        (path ""
          (reference "#PWR0130") (unit 1)
        )
      )
    )
  )

  (symbol (lib_id "antmicropower:GND") (at 326.39 48.26 0) (unit 1)
    (in_bom yes) (on_board yes) (dnp no)
    (property "Reference" "#PWR0110" (at 326.39 54.61 0)
      (effects (font (size 1.27 1.27)) hide)
    )
    (property "Value" "GND" (at 324.485 52.705 0)
      (effects (font (size 1.27 1.27) (thickness 0.15)) (justify left bottom))
    )
    (property "Footprint" "" (at 326.39 48.26 0)
      (effects (font (size 1.27 1.27) (thickness 0.15)) (justify left bottom) hide)
    )
    (property "Datasheet" "" (at 326.39 48.26 0)
      (effects (font (size 1.27 1.27) (thickness 0.15)) (justify left bottom) hide)
    )
    (property "Author" "Antmicro" (at 335.28 55.88 0)
      (effects (font (size 1.27 1.27) (thickness 0.15)) (justify left bottom) hide)
    )
    (property "License" "Apache-2.0" (at 335.28 58.42 0)
      (effects (font (size 1.27 1.27) (thickness 0.15)) (justify left bottom) hide)
    )
    (pin "1")
    (instances
      (project "antmicro-hdmi-mipi-bridge-hw"
        (path ""
          (reference "#PWR0110") (unit 1)
        )
      )
    )
  )

  (symbol (lib_id "antmicropower:PWR_FLAG") (at 210.82 205.105 0) (unit 1)
    (in_bom yes) (on_board yes) (dnp no)
    (property "Reference" "#FLG0104" (at 210.82 203.2 0)
      (effects (font (size 1.27 1.27)) hide)
    )
    (property "Value" "PWR_FLAG" (at 210.82 201.295 0)
      (effects (font (size 1.27 1.27)))
    )
    (property "Footprint" "" (at 210.82 205.105 0)
      (effects (font (size 1.27 1.27)) hide)
    )
    (property "Datasheet" "" (at 210.82 205.105 0)
      (effects (font (size 1.27 1.27)) hide)
    )
    (pin "1")
    (instances
      (project "antmicro-hdmi-mipi-bridge-hw"
        (path ""
          (reference "#FLG0104") (unit 1)
        )
      )
    )
  )

  (symbol (lib_id "antmicropower:GND") (at 231.14 231.14 0) (unit 1)
    (in_bom yes) (on_board yes) (dnp no)
    (property "Reference" "#PWR0118" (at 231.14 237.49 0)
      (effects (font (size 1.27 1.27)) hide)
    )
    (property "Value" "GND" (at 229.235 236.22 0)
      (effects (font (size 1.27 1.27) (thickness 0.15)) (justify left bottom))
    )
    (property "Footprint" "" (at 231.14 231.14 0)
      (effects (font (size 1.27 1.27) (thickness 0.15)) (justify left bottom) hide)
    )
    (property "Datasheet" "" (at 231.14 231.14 0)
      (effects (font (size 1.27 1.27) (thickness 0.15)) (justify left bottom) hide)
    )
    (property "Author" "Antmicro" (at 240.03 238.76 0)
      (effects (font (size 1.27 1.27) (thickness 0.15)) (justify left bottom) hide)
    )
    (property "License" "Apache-2.0" (at 240.03 241.3 0)
      (effects (font (size 1.27 1.27) (thickness 0.15)) (justify left bottom) hide)
    )
    (pin "1")
    (instances
      (project "antmicro-hdmi-mipi-bridge-hw"
        (path ""
          (reference "#PWR0118") (unit 1)
        )
      )
    )
  )

  (symbol (lib_id "antmicropower:+3V3") (at 292.1 36.83 0) (unit 1)
    (in_bom yes) (on_board yes) (dnp no) (fields_autoplaced)
    (property "Reference" "#PWR0124" (at 292.1 40.64 0)
      (effects (font (size 1.27 1.27)) hide)
    )
    (property "Value" "+3V3" (at 292.1 33.02 0)
      (effects (font (size 1.27 1.27) (thickness 0.15)) (justify left bottom))
    )
    (property "Footprint" "" (at 292.1 36.83 0)
      (effects (font (size 1.27 1.27) (thickness 0.15)) (justify left bottom) hide)
    )
    (property "Datasheet" "" (at 292.1 36.83 0)
      (effects (font (size 1.27 1.27) (thickness 0.15)) (justify left bottom) hide)
    )
    (property "Author" "Antmicro" (at 307.34 39.37 0)
      (effects (font (size 1.27 1.27) (thickness 0.15)) (justify left bottom) hide)
    )
    (property "License" "Apache-2.0" (at 307.34 41.91 0)
      (effects (font (size 1.27 1.27) (thickness 0.15)) (justify left bottom) hide)
    )
    (pin "1")
    (instances
      (project "antmicro-hdmi-mipi-bridge-hw"
        (path ""
          (reference "#PWR0124") (unit 1)
        )
      )
    )
  )

  (symbol (lib_id "antmicropower:+3V3") (at 330.2 203.2 0) (unit 1)
    (in_bom yes) (on_board yes) (dnp no)
    (property "Reference" "#PWR0133" (at 330.2 207.01 0)
      (effects (font (size 1.27 1.27)) hide)
    )
    (property "Value" "+3V3" (at 327.025 200.025 0)
      (effects (font (size 1.27 1.27) (thickness 0.15)) (justify left bottom))
    )
    (property "Footprint" "" (at 330.2 203.2 0)
      (effects (font (size 1.27 1.27) (thickness 0.15)) (justify left bottom) hide)
    )
    (property "Datasheet" "" (at 330.2 203.2 0)
      (effects (font (size 1.27 1.27) (thickness 0.15)) (justify left bottom) hide)
    )
    (property "Author" "Antmicro" (at 345.44 205.74 0)
      (effects (font (size 1.27 1.27) (thickness 0.15)) (justify left bottom) hide)
    )
    (property "License" "Apache-2.0" (at 345.44 208.28 0)
      (effects (font (size 1.27 1.27) (thickness 0.15)) (justify left bottom) hide)
    )
    (pin "1")
    (instances
      (project "antmicro-hdmi-mipi-bridge-hw"
        (path ""
          (reference "#PWR0133") (unit 1)
        )
      )
    )
  )

  (symbol (lib_id "antmicropower:GND") (at 316.23 48.26 0) (unit 1)
    (in_bom yes) (on_board yes) (dnp no)
    (property "Reference" "#PWR0123" (at 316.23 54.61 0)
      (effects (font (size 1.27 1.27)) hide)
    )
    (property "Value" "GND" (at 314.325 52.705 0)
      (effects (font (size 1.27 1.27) (thickness 0.15)) (justify left bottom))
    )
    (property "Footprint" "" (at 316.23 48.26 0)
      (effects (font (size 1.27 1.27) (thickness 0.15)) (justify left bottom) hide)
    )
    (property "Datasheet" "" (at 316.23 48.26 0)
      (effects (font (size 1.27 1.27) (thickness 0.15)) (justify left bottom) hide)
    )
    (property "Author" "Antmicro" (at 325.12 55.88 0)
      (effects (font (size 1.27 1.27) (thickness 0.15)) (justify left bottom) hide)
    )
    (property "License" "Apache-2.0" (at 325.12 58.42 0)
      (effects (font (size 1.27 1.27) (thickness 0.15)) (justify left bottom) hide)
    )
    (pin "1")
    (instances
      (project "antmicro-hdmi-mipi-bridge-hw"
        (path ""
          (reference "#PWR0123") (unit 1)
        )
      )
    )
  )

  (symbol (lib_id "antmicropower:GND") (at 302.26 48.26 0) (unit 1)
    (in_bom yes) (on_board yes) (dnp no)
    (property "Reference" "#PWR0122" (at 302.26 54.61 0)
      (effects (font (size 1.27 1.27)) hide)
    )
    (property "Value" "GND" (at 300.355 52.705 0)
      (effects (font (size 1.27 1.27) (thickness 0.15)) (justify left bottom))
    )
    (property "Footprint" "" (at 302.26 48.26 0)
      (effects (font (size 1.27 1.27) (thickness 0.15)) (justify left bottom) hide)
    )
    (property "Datasheet" "" (at 302.26 48.26 0)
      (effects (font (size 1.27 1.27) (thickness 0.15)) (justify left bottom) hide)
    )
    (property "Author" "Antmicro" (at 311.15 55.88 0)
      (effects (font (size 1.27 1.27) (thickness 0.15)) (justify left bottom) hide)
    )
    (property "License" "Apache-2.0" (at 311.15 58.42 0)
      (effects (font (size 1.27 1.27) (thickness 0.15)) (justify left bottom) hide)
    )
    (pin "1")
    (instances
      (project "antmicro-hdmi-mipi-bridge-hw"
        (path ""
          (reference "#PWR0122") (unit 1)
        )
      )
    )
  )

  (symbol (lib_id "antmicropower:PWR_FLAG") (at 210.82 159.385 0) (unit 1)
    (in_bom yes) (on_board yes) (dnp no)
    (property "Reference" "#FLG0102" (at 210.82 157.48 0)
      (effects (font (size 1.27 1.27)) hide)
    )
    (property "Value" "PWR_FLAG" (at 210.82 155.575 0)
      (effects (font (size 1.27 1.27)))
    )
    (property "Footprint" "" (at 210.82 159.385 0)
      (effects (font (size 1.27 1.27)) hide)
    )
    (property "Datasheet" "" (at 210.82 159.385 0)
      (effects (font (size 1.27 1.27)) hide)
    )
    (pin "1")
    (instances
      (project "antmicro-hdmi-mipi-bridge-hw"
        (path ""
          (reference "#FLG0102") (unit 1)
        )
      )
    )
  )

  (symbol (lib_id "antmicroLogicTranslatorsLevelShifters:PCA9517ATP") (at 335.28 97.79 0) (unit 1)
    (in_bom yes) (on_board yes) (dnp no)
    (property "Reference" "U3" (at 344.17 91.44 0)
      (effects (font (size 1.524 1.524)))
    )
    (property "Value" "PCA9517ATP" (at 337.82 94.615 0)
      (effects (font (size 1.27 1.27) (thickness 0.15)) (justify left bottom) hide)
    )
    (property "Footprint" "antmicro-footprints:SOT1069-2" (at 368.3 105.41 0)
      (effects (font (size 1.27 1.27) (thickness 0.15)) (justify left bottom) hide)
    )
    (property "Datasheet" "https://www.nxp.com/docs/en/data-sheet/PCA9517A.pdf" (at 368.3 107.95 0)
      (effects (font (size 1.27 1.27) (thickness 0.15)) (justify left bottom) hide)
    )
    (property "MPN" "PCA9517ATP" (at 337.82 94.615 0)
      (effects (font (size 1.27 1.27) (thickness 0.15)) (justify left bottom))
    )
    (property "Manufacturer" "NXP" (at 368.3 113.03 0)
      (effects (font (size 1.27 1.27) (thickness 0.15)) (justify left bottom) hide)
    )
    (property "Author" "Antmicro" (at 368.3 115.57 0)
      (effects (font (size 1.27 1.27) (thickness 0.15)) (justify left bottom) hide)
    )
    (property "License" "Apache-2.0" (at 368.3 118.11 0)
      (effects (font (size 1.27 1.27) (thickness 0.15)) (justify left bottom) hide)
    )
    (pin "1")
    (pin "2")
    (pin "3")
    (pin "4")
    (pin "5")
    (pin "6")
    (pin "7")
    (pin "8")
    (pin "9")
    (instances
      (project "antmicro-hdmi-mipi-bridge-hw"
        (path ""
          (reference "U3") (unit 1)
        )
      )
    )
  )

  (symbol (lib_id "antmicropower:+3V3") (at 307.34 81.28 0) (unit 1)
    (in_bom yes) (on_board yes) (dnp no)
    (property "Reference" "#PWR0121" (at 307.34 85.09 0)
      (effects (font (size 1.27 1.27)) hide)
    )
    (property "Value" "+3V3" (at 304.165 78.105 0)
      (effects (font (size 1.27 1.27) (thickness 0.15)) (justify left bottom))
    )
    (property "Footprint" "" (at 307.34 81.28 0)
      (effects (font (size 1.27 1.27) (thickness 0.15)) (justify left bottom) hide)
    )
    (property "Datasheet" "" (at 307.34 81.28 0)
      (effects (font (size 1.27 1.27) (thickness 0.15)) (justify left bottom) hide)
    )
    (property "Author" "Antmicro" (at 322.58 83.82 0)
      (effects (font (size 1.27 1.27) (thickness 0.15)) (justify left bottom) hide)
    )
    (property "License" "Apache-2.0" (at 322.58 86.36 0)
      (effects (font (size 1.27 1.27) (thickness 0.15)) (justify left bottom) hide)
    )
    (pin "1")
    (instances
      (project "antmicro-hdmi-mipi-bridge-hw"
        (path ""
          (reference "#PWR0121") (unit 1)
        )
      )
    )
  )

  (symbol (lib_id "antmicroCapacitors0402:C_100n_0402") (at 182.88 228.6 90) (unit 1)
    (in_bom yes) (on_board yes) (dnp no)
    (property "Reference" "C27" (at 175.895 225.425 90)
      (effects (font (size 1.524 1.524)) (justify right))
    )
    (property "Value" "C_100n_0402" (at 193.04 208.28 0)
      (effects (font (size 1.27 1.27) (thickness 0.15)) (justify left bottom) hide)
    )
    (property "Footprint" "antmicro-footprints:C_0402_1005Metric" (at 195.58 208.28 0)
      (effects (font (size 1.27 1.27) (thickness 0.15)) (justify left bottom) hide)
    )
    (property "Datasheet" "https://www.murata.com/products/productdetail?partno=GRM155R61H104KE14%23" (at 198.12 208.28 0)
      (effects (font (size 1.27 1.27) (thickness 0.15)) (justify left bottom) hide)
    )
    (property "Manufacturer" "Murata" (at 203.2 208.28 0)
      (effects (font (size 1.27 1.27) (thickness 0.15)) (justify left bottom) hide)
    )
    (property "MPN" "GRM155R61H104KE14D" (at 200.66 208.28 0)
      (effects (font (size 1.27 1.27) (thickness 0.15)) (justify left bottom) hide)
    )
    (property "Val" "100n" (at 180.34 227.33 90)
      (effects (font (size 1.27 1.27) (thickness 0.15)) (justify left bottom))
    )
    (property "License" "Apache-2.0" (at 205.74 208.28 0)
      (effects (font (size 1.27 1.27) (thickness 0.15)) (justify left bottom) hide)
    )
    (property "Author" "Antmicro" (at 208.28 208.28 0)
      (effects (font (size 1.27 1.27) (thickness 0.15)) (justify left bottom) hide)
    )
    (property "Voltage" "50V" (at 210.82 208.28 0)
      (effects (font (size 1.27 1.27)) (justify left bottom) hide)
    )
    (property "Dielectric" "X5R" (at 213.36 208.28 0)
      (effects (font (size 1.27 1.27)) (justify left bottom) hide)
    )
    (property "Public" "False" (at 215.9 208.28 0)
      (effects (font (size 1.27 1.27)) (justify left bottom) hide)
    )
    (pin "1")
    (pin "2")
    (instances
      (project "antmicro-hdmi-mipi-bridge-hw"
        (path ""
          (reference "C27") (unit 1)
        )
      )
    )
  )

  (symbol (lib_id "antmicropower:+5V") (at 381 81.28 0) (unit 1)
    (in_bom yes) (on_board yes) (dnp no)
    (property "Reference" "#PWR0111" (at 381 85.09 0)
      (effects (font (size 1.27 1.27)) hide)
    )
    (property "Value" "+5V" (at 378.46 78.105 0)
      (effects (font (size 1.27 1.27) (thickness 0.15)) (justify left bottom))
    )
    (property "Footprint" "" (at 381 81.28 0)
      (effects (font (size 1.27 1.27) (thickness 0.15)) (justify left bottom) hide)
    )
    (property "Datasheet" "" (at 381 81.28 0)
      (effects (font (size 1.27 1.27) (thickness 0.15)) (justify left bottom) hide)
    )
    (property "Author" "Antmicro" (at 396.24 88.9 0)
      (effects (font (size 1.27 1.27) (thickness 0.15)) (justify left bottom) hide)
    )
    (property "License" "Apache-2.0" (at 396.24 91.44 0)
      (effects (font (size 1.27 1.27) (thickness 0.15)) (justify left bottom) hide)
    )
    (pin "1")
    (instances
      (project "antmicro-hdmi-mipi-bridge-hw"
        (path ""
          (reference "#PWR0111") (unit 1)
        )
      )
    )
  )

  (symbol (lib_id "antmicroResistors0603:R_0R_0603") (at 119.38 97.79 180) (unit 1)
    (in_bom yes) (on_board yes) (dnp no)
    (property "Reference" "R1" (at 116.84 93.345 0)
      (effects (font (size 1.524 1.524)))
    )
    (property "Value" "R_0R_0603" (at 99.06 85.09 0)
      (effects (font (size 1.27 1.27) (thickness 0.15)) (justify left bottom) hide)
    )
    (property "Footprint" "antmicro-footprints:R_0603_1608Metric" (at 99.06 82.55 0)
      (effects (font (size 1.27 1.27) (thickness 0.15)) (justify left bottom) hide)
    )
    (property "Datasheet" "https://www.bourns.com/docs/product-datasheets/cr.pdf?sfvrsn=574d41f6_14" (at 99.06 80.01 0)
      (effects (font (size 1.27 1.27) (thickness 0.15)) (justify left bottom) hide)
    )
    (property "Manufacturer" "Bourns" (at 99.06 74.93 0)
      (effects (font (size 1.27 1.27) (thickness 0.15)) (justify left bottom) hide)
    )
    (property "MPN" "CR0603-J/-000ELF" (at 99.06 77.47 0)
      (effects (font (size 1.27 1.27) (thickness 0.15)) (justify left bottom) hide)
    )
    (property "Val" "0R" (at 118.11 94.615 0)
      (effects (font (size 1.27 1.27) (thickness 0.15)) (justify left bottom))
    )
    (property "License" "Apache-2.0" (at 99.06 72.39 0)
      (effects (font (size 1.27 1.27) (thickness 0.15)) (justify left bottom) hide)
    )
    (property "Author" "Antmicro" (at 99.06 69.85 0)
      (effects (font (size 1.27 1.27) (thickness 0.15)) (justify left bottom) hide)
    )
    (property "Tolerance" "~" (at 99.06 87.63 0)
      (effects (font (size 1.27 1.27)) (justify left bottom) hide)
    )
    (property "Current" "1A" (at 99.06 67.31 0)
      (effects (font (size 1.27 1.27) (thickness 0.15)) (justify left bottom) hide)
    )
    (property "Public" "False" (at 99.06 67.31 0)
      (effects (font (size 1.27 1.27)) (justify left bottom) hide)
    )
    (pin "1")
    (pin "2")
    (instances
      (project "antmicro-hdmi-mipi-bridge-hw"
        (path ""
          (reference "R1") (unit 1)
        )
      )
    )
  )

  (symbol (lib_id "antmicroCapacitors0402:C_100n_0402") (at 104.14 259.08 90) (unit 1)
    (in_bom yes) (on_board yes) (dnp no)
    (property "Reference" "C3" (at 100.33 255.27 90)
      (effects (font (size 1.524 1.524)) (justify left))
    )
    (property "Value" "C_100n_0402" (at 114.3 238.76 0)
      (effects (font (size 1.27 1.27) (thickness 0.15)) (justify left bottom) hide)
    )
    (property "Footprint" "antmicro-footprints:C_0402_1005Metric" (at 116.84 238.76 0)
      (effects (font (size 1.27 1.27) (thickness 0.15)) (justify left bottom) hide)
    )
    (property "Datasheet" "https://www.murata.com/products/productdetail?partno=GRM155R61H104KE14%23" (at 119.38 238.76 0)
      (effects (font (size 1.27 1.27) (thickness 0.15)) (justify left bottom) hide)
    )
    (property "Manufacturer" "Murata" (at 124.46 238.76 0)
      (effects (font (size 1.27 1.27) (thickness 0.15)) (justify left bottom) hide)
    )
    (property "MPN" "GRM155R61H104KE14D" (at 121.92 238.76 0)
      (effects (font (size 1.27 1.27) (thickness 0.15)) (justify left bottom) hide)
    )
    (property "Val" "100n" (at 101.6 257.81 90)
      (effects (font (size 1.27 1.27) (thickness 0.15)) (justify left bottom))
    )
    (property "License" "Apache-2.0" (at 127 238.76 0)
      (effects (font (size 1.27 1.27) (thickness 0.15)) (justify left bottom) hide)
    )
    (property "Author" "Antmicro" (at 129.54 238.76 0)
      (effects (font (size 1.27 1.27) (thickness 0.15)) (justify left bottom) hide)
    )
    (property "Voltage" "50V" (at 132.08 238.76 0)
      (effects (font (size 1.27 1.27)) (justify left bottom) hide)
    )
    (property "Dielectric" "X5R" (at 134.62 238.76 0)
      (effects (font (size 1.27 1.27)) (justify left bottom) hide)
    )
    (property "Public" "False" (at 137.16 238.76 0)
      (effects (font (size 1.27 1.27)) (justify left bottom) hide)
    )
    (pin "1")
    (pin "2")
    (instances
      (project "antmicro-hdmi-mipi-bridge-hw"
        (path ""
          (reference "C3") (unit 1)
        )
      )
    )
  )

  (symbol (lib_id "antmicropower:GND") (at 336.55 45.085 0) (unit 1)
    (in_bom yes) (on_board yes) (dnp no)
    (property "Reference" "#PWR0109" (at 336.55 51.435 0)
      (effects (font (size 1.27 1.27)) hide)
    )
    (property "Value" "GND" (at 334.645 49.53 0)
      (effects (font (size 1.27 1.27) (thickness 0.15)) (justify left bottom))
    )
    (property "Footprint" "" (at 336.55 45.085 0)
      (effects (font (size 1.27 1.27) (thickness 0.15)) (justify left bottom) hide)
    )
    (property "Datasheet" "" (at 336.55 45.085 0)
      (effects (font (size 1.27 1.27) (thickness 0.15)) (justify left bottom) hide)
    )
    (property "Author" "Antmicro" (at 345.44 52.705 0)
      (effects (font (size 1.27 1.27) (thickness 0.15)) (justify left bottom) hide)
    )
    (property "License" "Apache-2.0" (at 345.44 55.245 0)
      (effects (font (size 1.27 1.27) (thickness 0.15)) (justify left bottom) hide)
    )
    (pin "1")
    (instances
      (project "antmicro-hdmi-mipi-bridge-hw"
        (path ""
          (reference "#PWR0109") (unit 1)
        )
      )
    )
  )

  (symbol (lib_id "antmicroCapacitors0402:C_470p_0402") (at 219.71 223.52 270) (unit 1)
    (in_bom yes) (on_board yes) (dnp no)
    (property "Reference" "C6" (at 217.17 225.425 90)
      (effects (font (size 1.524 1.524)) (justify right))
    )
    (property "Value" "C_470p_0402" (at 209.55 243.84 0)
      (effects (font (size 1.27 1.27) (thickness 0.15)) (justify left bottom) hide)
    )
    (property "Footprint" "antmicro-footprints:C_0402_1005Metric" (at 207.01 243.84 0)
      (effects (font (size 1.27 1.27) (thickness 0.15)) (justify left bottom) hide)
    )
    (property "Datasheet" "https://www.passivecomponent.com/wp-content/uploads/datasheet/WTC_MLCC_General_Purpose.pdf" (at 204.47 243.84 0)
      (effects (font (size 1.27 1.27) (thickness 0.15)) (justify left bottom) hide)
    )
    (property "Manufacturer" "Walsin" (at 199.39 243.84 0)
      (effects (font (size 1.27 1.27) (thickness 0.15)) (justify left bottom) hide)
    )
    (property "MPN" "0402B471K250CT" (at 201.93 243.84 0)
      (effects (font (size 1.27 1.27) (thickness 0.15)) (justify left bottom) hide)
    )
    (property "Val" "470p" (at 213.995 227.965 90)
      (effects (font (size 1.27 1.27) (thickness 0.15)) (justify left bottom))
    )
    (property "License" "Apache-2.0" (at 196.85 243.84 0)
      (effects (font (size 1.27 1.27) (thickness 0.15)) (justify left bottom) hide)
    )
    (property "Author" "Antmicro" (at 194.31 243.84 0)
      (effects (font (size 1.27 1.27) (thickness 0.15)) (justify left bottom) hide)
    )
    (property "Voltage" "" (at 191.77 243.84 0)
      (effects (font (size 1.27 1.27)) (justify left bottom) hide)
    )
    (property "Dielectric" "" (at 189.23 243.84 0)
      (effects (font (size 1.27 1.27)) (justify left bottom) hide)
    )
    (property "Public" "False" (at 186.69 243.84 0)
      (effects (font (size 1.27 1.27)) (justify left bottom) hide)
    )
    (pin "1")
    (pin "2")
    (instances
      (project "antmicro-hdmi-mipi-bridge-hw"
        (path ""
          (reference "C6") (unit 1)
        )
      )
    )
  )

  (symbol (lib_id "antmicroResistors0603:R_0R_0603") (at 119.38 104.14 180) (unit 1)
    (in_bom yes) (on_board yes) (dnp no)
    (property "Reference" "R2" (at 116.84 106.68 0)
      (effects (font (size 1.524 1.524)))
    )
    (property "Value" "R_0R_0603" (at 99.06 91.44 0)
      (effects (font (size 1.27 1.27) (thickness 0.15)) (justify left bottom) hide)
    )
    (property "Footprint" "antmicro-footprints:R_0603_1608Metric" (at 99.06 88.9 0)
      (effects (font (size 1.27 1.27) (thickness 0.15)) (justify left bottom) hide)
    )
    (property "Datasheet" "https://www.bourns.com/docs/product-datasheets/cr.pdf?sfvrsn=574d41f6_14" (at 99.06 86.36 0)
      (effects (font (size 1.27 1.27) (thickness 0.15)) (justify left bottom) hide)
    )
    (property "Manufacturer" "Bourns" (at 99.06 81.28 0)
      (effects (font (size 1.27 1.27) (thickness 0.15)) (justify left bottom) hide)
    )
    (property "MPN" "CR0603-J/-000ELF" (at 99.06 83.82 0)
      (effects (font (size 1.27 1.27) (thickness 0.15)) (justify left bottom) hide)
    )
    (property "Val" "0R" (at 118.11 107.95 0)
      (effects (font (size 1.27 1.27) (thickness 0.15)) (justify left bottom))
    )
    (property "License" "Apache-2.0" (at 99.06 78.74 0)
      (effects (font (size 1.27 1.27) (thickness 0.15)) (justify left bottom) hide)
    )
    (property "Author" "Antmicro" (at 99.06 76.2 0)
      (effects (font (size 1.27 1.27) (thickness 0.15)) (justify left bottom) hide)
    )
    (property "Tolerance" "~" (at 99.06 93.98 0)
      (effects (font (size 1.27 1.27)) (justify left bottom) hide)
    )
    (property "Current" "1A" (at 99.06 73.66 0)
      (effects (font (size 1.27 1.27) (thickness 0.15)) (justify left bottom) hide)
    )
    (property "Public" "False" (at 99.06 73.66 0)
      (effects (font (size 1.27 1.27)) (justify left bottom) hide)
    )
    (pin "1")
    (pin "2")
    (instances
      (project "antmicro-hdmi-mipi-bridge-hw"
        (path ""
          (reference "R2") (unit 1)
        )
      )
    )
  )

  (symbol (lib_id "antmicroInterfaceControllers:TC358743XBG") (at 154.94 175.26 0) (unit 2)
    (in_bom yes) (on_board yes) (dnp no) (fields_autoplaced)
    (property "Reference" "U1" (at 167.64 167.64 0)
      (effects (font (size 1.27 1.27) (thickness 0.15)))
    )
    (property "Value" "TC358743XBG" (at 195.58 167.64 0)
      (effects (font (size 1.27 1.27) (thickness 0.15)) (justify left bottom) hide)
    )
    (property "Footprint" "antmicro-footprints:BGA-64_8x8_6.0x6.0mm" (at 195.58 170.18 0)
      (effects (font (size 1.27 1.27) (thickness 0.15)) (justify left bottom) hide)
    )
    (property "Datasheet" "https://toshiba.semicon-storage.com/info/TC358743XBG_datasheet_en_20171026.pdf?did=35655&prodName=TC358743XBG" (at 195.58 172.72 0)
      (effects (font (size 1.27 1.27) (thickness 0.15)) (justify left bottom) hide)
    )
    (property "MPN" "TC358743XBG" (at 167.64 170.18 0)
      (effects (font (size 1.27 1.27) (thickness 0.15)))
    )
    (property "Manufacturer" "Toshiba" (at 195.58 177.8 0)
      (effects (font (size 1.27 1.27) (thickness 0.15)) (justify left bottom) hide)
    )
    (property "Author" "Antmicro" (at 195.58 180.34 0)
      (effects (font (size 1.27 1.27) (thickness 0.15)) (justify left bottom) hide)
    )
    (property "License" "Apache-2.0" (at 195.58 182.88 0)
      (effects (font (size 1.27 1.27) (thickness 0.15)) (justify left bottom) hide)
    )
    (pin "H6")
    (pin "A8")
    (pin "G2")
    (pin "F5")
    (pin "F7")
    (pin "D2")
    (pin "B5")
    (pin "D1")
    (pin "H7")
    (pin "A3")
    (pin "B7")
    (pin "D7")
    (pin "B1")
    (pin "B6")
    (pin "F4")
    (pin "G8")
    (pin "E5")
    (pin "B2")
    (pin "D4")
    (pin "H8")
    (pin "F6")
    (pin "B3")
    (pin "F1")
    (pin "F3")
    (pin "G6")
    (pin "G4")
    (pin "D5")
    (pin "C5")
    (pin "D3")
    (pin "G1")
    (pin "E4")
    (pin "E2")
    (pin "C3")
    (pin "D8")
    (pin "B8")
    (pin "H3")
    (pin "A1")
    (pin "A5")
    (pin "E7")
    (pin "G5")
    (pin "A7")
    (pin "E6")
    (pin "G3")
    (pin "C8")
    (pin "F2")
    (pin "C6")
    (pin "A2")
    (pin "H2")
    (pin "G7")
    (pin "D6")
    (pin "C1")
    (pin "E8")
    (pin "C7")
    (pin "A6")
    (pin "E1")
    (pin "C2")
    (pin "F8")
    (pin "B4")
    (pin "E3")
    (pin "H5")
    (pin "H4")
    (pin "C4")
    (pin "A4")
    (pin "H1")
    (instances
      (project "antmicro-hdmi-mipi-bridge-hw"
        (path ""
          (reference "U1") (unit 2)
        )
      )
    )
  )

  (symbol (lib_id "antmicropower:+3V3") (at 185.42 46.99 0) (unit 1)
    (in_bom yes) (on_board yes) (dnp no)
    (property "Reference" "#PWR0126" (at 185.42 50.8 0)
      (effects (font (size 1.27 1.27)) hide)
    )
    (property "Value" "+3V3" (at 182.245 43.815 0)
      (effects (font (size 1.27 1.27) (thickness 0.15)) (justify left bottom))
    )
    (property "Footprint" "" (at 185.42 46.99 0)
      (effects (font (size 1.27 1.27) (thickness 0.15)) (justify left bottom) hide)
    )
    (property "Datasheet" "" (at 185.42 46.99 0)
      (effects (font (size 1.27 1.27) (thickness 0.15)) (justify left bottom) hide)
    )
    (property "Author" "Antmicro" (at 200.66 49.53 0)
      (effects (font (size 1.27 1.27) (thickness 0.15)) (justify left bottom) hide)
    )
    (property "License" "Apache-2.0" (at 200.66 52.07 0)
      (effects (font (size 1.27 1.27) (thickness 0.15)) (justify left bottom) hide)
    )
    (pin "1")
    (instances
      (project "antmicro-hdmi-mipi-bridge-hw"
        (path ""
          (reference "#PWR0126") (unit 1)
        )
      )
    )
  )

  (symbol (lib_id "antmicropower:GND") (at 353.06 209.55 0) (unit 1)
    (in_bom yes) (on_board yes) (dnp no)
    (property "Reference" "#PWR0129" (at 353.06 215.9 0)
      (effects (font (size 1.27 1.27)) hide)
    )
    (property "Value" "GND" (at 351.155 213.995 0)
      (effects (font (size 1.27 1.27) (thickness 0.15)) (justify left bottom))
    )
    (property "Footprint" "" (at 353.06 209.55 0)
      (effects (font (size 1.27 1.27) (thickness 0.15)) (justify left bottom) hide)
    )
    (property "Datasheet" "" (at 353.06 209.55 0)
      (effects (font (size 1.27 1.27) (thickness 0.15)) (justify left bottom) hide)
    )
    (property "Author" "Antmicro" (at 361.95 217.17 0)
      (effects (font (size 1.27 1.27) (thickness 0.15)) (justify left bottom) hide)
    )
    (property "License" "Apache-2.0" (at 361.95 219.71 0)
      (effects (font (size 1.27 1.27) (thickness 0.15)) (justify left bottom) hide)
    )
    (pin "1")
    (instances
      (project "antmicro-hdmi-mipi-bridge-hw"
        (path ""
          (reference "#PWR0129") (unit 1)
        )
      )
    )
  )

  (symbol (lib_id "antmicropower:GND") (at 358.14 184.15 0) (unit 1)
    (in_bom yes) (on_board yes) (dnp no)
    (property "Reference" "#PWR0128" (at 358.14 190.5 0)
      (effects (font (size 1.27 1.27)) hide)
    )
    (property "Value" "GND" (at 356.235 188.595 0)
      (effects (font (size 1.27 1.27) (thickness 0.15)) (justify left bottom))
    )
    (property "Footprint" "" (at 358.14 184.15 0)
      (effects (font (size 1.27 1.27) (thickness 0.15)) (justify left bottom) hide)
    )
    (property "Datasheet" "" (at 358.14 184.15 0)
      (effects (font (size 1.27 1.27) (thickness 0.15)) (justify left bottom) hide)
    )
    (property "Author" "Antmicro" (at 367.03 191.77 0)
      (effects (font (size 1.27 1.27) (thickness 0.15)) (justify left bottom) hide)
    )
    (property "License" "Apache-2.0" (at 367.03 194.31 0)
      (effects (font (size 1.27 1.27) (thickness 0.15)) (justify left bottom) hide)
    )
    (pin "1")
    (instances
      (project "antmicro-hdmi-mipi-bridge-hw"
        (path ""
          (reference "#PWR0128") (unit 1)
        )
      )
    )
  )

  (symbol (lib_id "antmicropower:GND") (at 185.42 69.85 0) (unit 1)
    (in_bom yes) (on_board yes) (dnp no)
    (property "Reference" "#PWR0140" (at 185.42 76.2 0)
      (effects (font (size 1.27 1.27)) hide)
    )
    (property "Value" "GND" (at 183.515 74.295 0)
      (effects (font (size 1.27 1.27) (thickness 0.15)) (justify left bottom))
    )
    (property "Footprint" "" (at 185.42 69.85 0)
      (effects (font (size 1.27 1.27) (thickness 0.15)) (justify left bottom) hide)
    )
    (property "Datasheet" "" (at 185.42 69.85 0)
      (effects (font (size 1.27 1.27) (thickness 0.15)) (justify left bottom) hide)
    )
    (property "Author" "Antmicro" (at 194.31 77.47 0)
      (effects (font (size 1.27 1.27) (thickness 0.15)) (justify left bottom) hide)
    )
    (property "License" "Apache-2.0" (at 194.31 80.01 0)
      (effects (font (size 1.27 1.27) (thickness 0.15)) (justify left bottom) hide)
    )
    (pin "1")
    (instances
      (project "antmicro-hdmi-mipi-bridge-hw"
        (path ""
          (reference "#PWR0140") (unit 1)
        )
      )
    )
  )

  (symbol (lib_id "antmicroFerriteBeadsandChips:FB_1kZ_0.8A_WE-CBF_0805") (at 245.11 220.98 0) (unit 1)
    (in_bom yes) (on_board yes) (dnp no)
    (property "Reference" "FB4" (at 247.65 215.9 0)
      (effects (font (size 1.524 1.524)))
    )
    (property "Value" "FB_1kZ_0.8A_WE-CBF_0805" (at 260.35 229.108 0)
      (effects (font (size 1.27 1.27) (thickness 0.15)) (justify left bottom) hide)
    )
    (property "Footprint" "antmicro-footprints:FB_0805_2012Metric" (at 260.35 231.648 0)
      (effects (font (size 1.27 1.27) (thickness 0.15)) (justify left bottom) hide)
    )
    (property "Datasheet" "https://www.we-online.com/components/products/datasheet/742792096.pdf" (at 260.35 234.188 0)
      (effects (font (size 1.27 1.27) (thickness 0.15)) (justify left bottom) hide)
    )
    (property "MPN" "742792096" (at 260.35 223.52 0)
      (effects (font (size 1.27 1.27) (thickness 0.15)) (justify left bottom) hide)
    )
    (property "Manufacturer" "Würth Elektronik" (at 260.35 236.728 0)
      (effects (font (size 1.27 1.27) (thickness 0.15)) (justify left bottom) hide)
    )
    (property "Author" "Antmicro" (at 260.35 239.268 0)
      (effects (font (size 1.27 1.27) (thickness 0.15)) (justify left bottom) hide)
    )
    (property "License" "Apache-2.0" (at 260.35 241.808 0)
      (effects (font (size 1.27 1.27) (thickness 0.15)) (justify left bottom) hide)
    )
    (property "Val" "1kZ/0.8A" (at 243.205 218.44 0)
      (effects (font (size 1.27 1.27)) (justify left bottom))
    )
    (property "Current" "" (at 265.43 243.84 0)
      (effects (font (size 1.27 1.27) (thickness 0.15)) (justify left bottom) hide)
    )
    (property "Public" "False" (at 265.43 236.22 0)
      (effects (font (size 1.27 1.27)) (justify left bottom) hide)
    )
    (pin "1")
    (pin "2")
    (instances
      (project "antmicro-hdmi-mipi-bridge-hw"
        (path ""
          (reference "FB4") (unit 1)
        )
      )
    )
  )

  (symbol (lib_id "antmicroResistors0402:R_10k_0402") (at 146.05 171.45 90) (unit 1)
    (in_bom yes) (on_board yes) (dnp no)
    (property "Reference" "R3" (at 140.97 167.64 90)
      (effects (font (size 1.524 1.524)) (justify right))
    )
    (property "Value" "R_10k_0402" (at 158.75 151.13 0)
      (effects (font (size 1.27 1.27) (thickness 0.15)) (justify left bottom) hide)
    )
    (property "Footprint" "antmicro-footprints:R_0402_1005Metric" (at 161.29 151.13 0)
      (effects (font (size 1.27 1.27) (thickness 0.15)) (justify left bottom) hide)
    )
    (property "Datasheet" "https://www.bourns.com/docs/product-datasheets/cr.pdf" (at 163.83 151.13 0)
      (effects (font (size 1.27 1.27) (thickness 0.15)) (justify left bottom) hide)
    )
    (property "Manufacturer" "Bourns" (at 168.91 151.13 0)
      (effects (font (size 1.27 1.27) (thickness 0.15)) (justify left bottom) hide)
    )
    (property "MPN" "CR0402-FX-1002GLF" (at 166.37 151.13 0)
      (effects (font (size 1.27 1.27) (thickness 0.15)) (justify left bottom) hide)
    )
    (property "Val" "10k" (at 144.78 169.545 90)
      (effects (font (size 1.27 1.27) (thickness 0.15)) (justify left bottom))
    )
    (property "License" "Apache-2.0" (at 171.45 151.13 0)
      (effects (font (size 1.27 1.27) (thickness 0.15)) (justify left bottom) hide)
    )
    (property "Author" "Antmicro" (at 173.99 151.13 0)
      (effects (font (size 1.27 1.27) (thickness 0.15)) (justify left bottom) hide)
    )
    (property "Tolerance" "1%" (at 156.21 151.13 0)
      (effects (font (size 1.27 1.27)) (justify left bottom) hide)
    )
    (property "Public" "False" (at 176.53 151.13 0)
      (effects (font (size 1.27 1.27)) (justify left bottom) hide)
    )
    (pin "1")
    (pin "2")
    (instances
      (project "antmicro-hdmi-mipi-bridge-hw"
        (path ""
          (reference "R3") (unit 1)
        )
      )
    )
  )

  (symbol (lib_id "antmicroInterfaceControllers:TC358743XBG") (at 106.68 229.87 0) (unit 3)
    (in_bom yes) (on_board yes) (dnp no)
    (property "Reference" "U1" (at 114.935 224.155 0)
      (effects (font (size 1.27 1.27) (thickness 0.15)) (justify left))
    )
    (property "Value" "TC358743XBG" (at 147.32 222.25 0)
      (effects (font (size 1.27 1.27) (thickness 0.15)) (justify left bottom) hide)
    )
    (property "Footprint" "antmicro-footprints:BGA-64_8x8_6.0x6.0mm" (at 147.32 224.79 0)
      (effects (font (size 1.27 1.27) (thickness 0.15)) (justify left bottom) hide)
    )
    (property "Datasheet" "https://toshiba.semicon-storage.com/info/TC358743XBG_datasheet_en_20171026.pdf?did=35655&prodName=TC358743XBG" (at 147.32 227.33 0)
      (effects (font (size 1.27 1.27) (thickness 0.15)) (justify left bottom) hide)
    )
    (property "MPN" "TC358743XBG" (at 109.855 226.06 0)
      (effects (font (size 1.27 1.27) (thickness 0.15)) (justify left))
    )
    (property "Manufacturer" "Toshiba" (at 147.32 232.41 0)
      (effects (font (size 1.27 1.27) (thickness 0.15)) (justify left bottom) hide)
    )
    (property "Author" "Antmicro" (at 147.32 234.95 0)
      (effects (font (size 1.27 1.27) (thickness 0.15)) (justify left bottom) hide)
    )
    (property "License" "Apache-2.0" (at 147.32 237.49 0)
      (effects (font (size 1.27 1.27) (thickness 0.15)) (justify left bottom) hide)
    )
    (pin "H6")
    (pin "A8")
    (pin "G2")
    (pin "F5")
    (pin "F7")
    (pin "D2")
    (pin "B5")
    (pin "D1")
    (pin "H7")
    (pin "A3")
    (pin "B7")
    (pin "D7")
    (pin "B1")
    (pin "B6")
    (pin "F4")
    (pin "G8")
    (pin "E5")
    (pin "B2")
    (pin "D4")
    (pin "H8")
    (pin "F6")
    (pin "B3")
    (pin "F1")
    (pin "F3")
    (pin "G6")
    (pin "G4")
    (pin "D5")
    (pin "C5")
    (pin "D3")
    (pin "G1")
    (pin "E4")
    (pin "E2")
    (pin "C3")
    (pin "D8")
    (pin "B8")
    (pin "H3")
    (pin "A1")
    (pin "A5")
    (pin "E7")
    (pin "G5")
    (pin "A7")
    (pin "E6")
    (pin "G3")
    (pin "C8")
    (pin "F2")
    (pin "C6")
    (pin "A2")
    (pin "H2")
    (pin "G7")
    (pin "D6")
    (pin "C1")
    (pin "E8")
    (pin "C7")
    (pin "A6")
    (pin "E1")
    (pin "C2")
    (pin "F8")
    (pin "B4")
    (pin "E3")
    (pin "H5")
    (pin "H4")
    (pin "C4")
    (pin "A4")
    (pin "H1")
    (instances
      (project "antmicro-hdmi-mipi-bridge-hw"
        (path ""
          (reference "U1") (unit 3)
        )
      )
    )
  )

  (symbol (lib_id "antmicroResistors0603:R_0R_0603") (at 228.6 160.02 0) (unit 1)
    (in_bom yes) (on_board yes) (dnp no)
    (property "Reference" "R7" (at 231.14 155.575 0)
      (effects (font (size 1.524 1.524)))
    )
    (property "Value" "R_0R_0603" (at 248.92 172.72 0)
      (effects (font (size 1.27 1.27) (thickness 0.15)) (justify left bottom) hide)
    )
    (property "Footprint" "antmicro-footprints:R_0603_1608Metric" (at 248.92 175.26 0)
      (effects (font (size 1.27 1.27) (thickness 0.15)) (justify left bottom) hide)
    )
    (property "Datasheet" "https://www.bourns.com/docs/product-datasheets/cr.pdf?sfvrsn=574d41f6_14" (at 248.92 177.8 0)
      (effects (font (size 1.27 1.27) (thickness 0.15)) (justify left bottom) hide)
    )
    (property "Manufacturer" "Bourns" (at 248.92 182.88 0)
      (effects (font (size 1.27 1.27) (thickness 0.15)) (justify left bottom) hide)
    )
    (property "MPN" "CR0603-J/-000ELF" (at 248.92 180.34 0)
      (effects (font (size 1.27 1.27) (thickness 0.15)) (justify left bottom) hide)
    )
    (property "Val" "0R" (at 229.87 158.115 0)
      (effects (font (size 1.27 1.27) (thickness 0.15)) (justify left bottom))
    )
    (property "License" "Apache-2.0" (at 248.92 185.42 0)
      (effects (font (size 1.27 1.27) (thickness 0.15)) (justify left bottom) hide)
    )
    (property "Author" "Antmicro" (at 248.92 187.96 0)
      (effects (font (size 1.27 1.27) (thickness 0.15)) (justify left bottom) hide)
    )
    (property "Tolerance" "~" (at 248.92 170.18 0)
      (effects (font (size 1.27 1.27)) (justify left bottom) hide)
    )
    (property "Current" "1A" (at 248.92 190.5 0)
      (effects (font (size 1.27 1.27) (thickness 0.15)) (justify left bottom) hide)
    )
    (property "Public" "False" (at 248.92 190.5 0)
      (effects (font (size 1.27 1.27)) (justify left bottom) hide)
    )
    (pin "1")
    (pin "2")
    (instances
      (project "antmicro-hdmi-mipi-bridge-hw"
        (path ""
          (reference "R7") (unit 1)
        )
      )
    )
  )

  (symbol (lib_id "antmicroResistors0402:R_10k_0402") (at 327.66 92.71 270) (mirror x) (unit 1)
    (in_bom yes) (on_board yes) (dnp no)
    (property "Reference" "R10" (at 325.755 90.805 90)
      (effects (font (size 1.524 1.524)) (justify right))
    )
    (property "Value" "R_10k_0402" (at 314.96 72.39 0)
      (effects (font (size 1.27 1.27) (thickness 0.15)) (justify left bottom) hide)
    )
    (property "Footprint" "antmicro-footprints:R_0402_1005Metric" (at 312.42 72.39 0)
      (effects (font (size 1.27 1.27) (thickness 0.15)) (justify left bottom) hide)
    )
    (property "Datasheet" "https://www.bourns.com/docs/product-datasheets/cr.pdf" (at 309.88 72.39 0)
      (effects (font (size 1.27 1.27) (thickness 0.15)) (justify left bottom) hide)
    )
    (property "Manufacturer" "Bourns" (at 304.8 72.39 0)
      (effects (font (size 1.27 1.27) (thickness 0.15)) (justify left bottom) hide)
    )
    (property "MPN" "CR0402-FX-1002GLF" (at 307.34 72.39 0)
      (effects (font (size 1.27 1.27) (thickness 0.15)) (justify left bottom) hide)
    )
    (property "Val" "10k" (at 321.945 92.71 90)
      (effects (font (size 1.27 1.27) (thickness 0.15)) (justify left bottom))
    )
    (property "License" "Apache-2.0" (at 302.26 72.39 0)
      (effects (font (size 1.27 1.27) (thickness 0.15)) (justify left bottom) hide)
    )
    (property "Author" "Antmicro" (at 299.72 72.39 0)
      (effects (font (size 1.27 1.27) (thickness 0.15)) (justify left bottom) hide)
    )
    (property "Tolerance" "1%" (at 317.5 72.39 0)
      (effects (font (size 1.27 1.27)) (justify left bottom) hide)
    )
    (property "Public" "False" (at 297.18 72.39 0)
      (effects (font (size 1.27 1.27)) (justify left bottom) hide)
    )
    (pin "1")
    (pin "2")
    (instances
      (project "antmicro-hdmi-mipi-bridge-hw"
        (path ""
          (reference "R10") (unit 1)
        )
      )
    )
  )

  (symbol (lib_id "antmicropower:GND") (at 219.71 185.42 0) (unit 1)
    (in_bom yes) (on_board yes) (dnp no)
    (property "Reference" "#PWR0156" (at 219.71 191.77 0)
      (effects (font (size 1.27 1.27)) hide)
    )
    (property "Value" "GND" (at 221.615 187.96 0)
      (effects (font (size 1.27 1.27) (thickness 0.15)) (justify left bottom))
    )
    (property "Footprint" "" (at 219.71 185.42 0)
      (effects (font (size 1.27 1.27) (thickness 0.15)) (justify left bottom) hide)
    )
    (property "Datasheet" "" (at 219.71 185.42 0)
      (effects (font (size 1.27 1.27) (thickness 0.15)) (justify left bottom) hide)
    )
    (property "Author" "Antmicro" (at 228.6 193.04 0)
      (effects (font (size 1.27 1.27) (thickness 0.15)) (justify left bottom) hide)
    )
    (property "License" "Apache-2.0" (at 228.6 195.58 0)
      (effects (font (size 1.27 1.27) (thickness 0.15)) (justify left bottom) hide)
    )
    (pin "1")
    (instances
      (project "antmicro-hdmi-mipi-bridge-hw"
        (path ""
          (reference "#PWR0156") (unit 1)
        )
      )
    )
  )

  (symbol (lib_id "antmicroCapacitors0603:C_10u_0603") (at 358.14 214.63 90) (unit 1)
    (in_bom yes) (on_board yes) (dnp no)
    (property "Reference" "C20" (at 365.125 212.09 90)
      (effects (font (size 1.524 1.524)) (justify left))
    )
    (property "Value" "C_10u_0603" (at 368.3 194.31 0)
      (effects (font (size 1.27 1.27) (thickness 0.15)) (justify left bottom) hide)
    )
    (property "Footprint" "antmicro-footprints:C_0603_1608Metric" (at 370.84 194.31 0)
      (effects (font (size 1.27 1.27) (thickness 0.15)) (justify left bottom) hide)
    )
    (property "Datasheet" "https://www.murata.com/products/productdetail?partno=GRM188R61A106KE69%23" (at 373.38 194.31 0)
      (effects (font (size 1.27 1.27) (thickness 0.15)) (justify left bottom) hide)
    )
    (property "Manufacturer" "Murata" (at 378.46 194.31 0)
      (effects (font (size 1.27 1.27) (thickness 0.15)) (justify left bottom) hide)
    )
    (property "MPN" "GRM188R61A106KE69D" (at 375.92 194.31 0)
      (effects (font (size 1.27 1.27) (thickness 0.15)) (justify left bottom) hide)
    )
    (property "Val" "10u" (at 364.49 213.36 90)
      (effects (font (size 1.27 1.27) (thickness 0.15)) (justify left bottom))
    )
    (property "License" "Apache-2.0" (at 381 194.31 0)
      (effects (font (size 1.27 1.27) (thickness 0.15)) (justify left bottom) hide)
    )
    (property "Author" "Antmicro" (at 383.54 194.31 0)
      (effects (font (size 1.27 1.27) (thickness 0.15)) (justify left bottom) hide)
    )
    (property "Voltage" "" (at 386.08 194.31 0)
      (effects (font (size 1.27 1.27)) (justify left bottom) hide)
    )
    (property "Dielectric" "template_dielectric" (at 388.62 194.31 0)
      (effects (font (size 1.27 1.27)) (justify left bottom) hide)
    )
    (property "Public" "False" (at 391.16 194.31 0)
      (effects (font (size 1.27 1.27)) (justify left bottom) hide)
    )
    (pin "1")
    (pin "2")
    (instances
      (project "antmicro-hdmi-mipi-bridge-hw"
        (path ""
          (reference "C20") (unit 1)
        )
      )
    )
  )

  (symbol (lib_id "antmicropower:PWR_FLAG") (at 210.82 238.125 0) (unit 1)
    (in_bom yes) (on_board yes) (dnp no)
    (property "Reference" "#FLG0107" (at 210.82 236.22 0)
      (effects (font (size 1.27 1.27)) hide)
    )
    (property "Value" "PWR_FLAG" (at 210.82 234.315 0)
      (effects (font (size 1.27 1.27)))
    )
    (property "Footprint" "" (at 210.82 238.125 0)
      (effects (font (size 1.27 1.27)) hide)
    )
    (property "Datasheet" "" (at 210.82 238.125 0)
      (effects (font (size 1.27 1.27)) hide)
    )
    (pin "1")
    (instances
      (project "antmicro-hdmi-mipi-bridge-hw"
        (path ""
          (reference "#FLG0107") (unit 1)
        )
      )
    )
  )

  (symbol (lib_id "antmicropower:GND") (at 330.2 184.15 0) (unit 1)
    (in_bom yes) (on_board yes) (dnp no)
    (property "Reference" "#PWR0132" (at 330.2 190.5 0)
      (effects (font (size 1.27 1.27)) hide)
    )
    (property "Value" "GND" (at 328.295 188.595 0)
      (effects (font (size 1.27 1.27) (thickness 0.15)) (justify left bottom))
    )
    (property "Footprint" "" (at 330.2 184.15 0)
      (effects (font (size 1.27 1.27) (thickness 0.15)) (justify left bottom) hide)
    )
    (property "Datasheet" "" (at 330.2 184.15 0)
      (effects (font (size 1.27 1.27) (thickness 0.15)) (justify left bottom) hide)
    )
    (property "Author" "Antmicro" (at 339.09 191.77 0)
      (effects (font (size 1.27 1.27) (thickness 0.15)) (justify left bottom) hide)
    )
    (property "License" "Apache-2.0" (at 339.09 194.31 0)
      (effects (font (size 1.27 1.27) (thickness 0.15)) (justify left bottom) hide)
    )
    (pin "1")
    (instances
      (project "antmicro-hdmi-mipi-bridge-hw"
        (path ""
          (reference "#PWR0132") (unit 1)
        )
      )
    )
  )

  (symbol (lib_id "antmicropower:PWR_FLAG") (at 113.665 84.455 90) (unit 1)
    (in_bom yes) (on_board yes) (dnp no) (fields_autoplaced)
    (property "Reference" "#FLG0108" (at 111.76 84.455 0)
      (effects (font (size 1.27 1.27)) hide)
    )
    (property "Value" "PWR_FLAG" (at 110.49 84.4549 90)
      (effects (font (size 1.27 1.27)) (justify left))
    )
    (property "Footprint" "" (at 113.665 84.455 0)
      (effects (font (size 1.27 1.27)) hide)
    )
    (property "Datasheet" "" (at 113.665 84.455 0)
      (effects (font (size 1.27 1.27)) hide)
    )
    (pin "1")
    (instances
      (project "antmicro-hdmi-mipi-bridge-hw"
        (path ""
          (reference "#FLG0108") (unit 1)
        )
      )
    )
  )

  (symbol (lib_id "antmicroResistors0603:R_0R_0603") (at 228.6 144.78 0) (unit 1)
    (in_bom yes) (on_board yes) (dnp no)
    (property "Reference" "R6" (at 231.14 140.335 0)
      (effects (font (size 1.524 1.524)))
    )
    (property "Value" "R_0R_0603" (at 248.92 157.48 0)
      (effects (font (size 1.27 1.27) (thickness 0.15)) (justify left bottom) hide)
    )
    (property "Footprint" "antmicro-footprints:R_0603_1608Metric" (at 248.92 160.02 0)
      (effects (font (size 1.27 1.27) (thickness 0.15)) (justify left bottom) hide)
    )
    (property "Datasheet" "https://www.bourns.com/docs/product-datasheets/cr.pdf?sfvrsn=574d41f6_14" (at 248.92 162.56 0)
      (effects (font (size 1.27 1.27) (thickness 0.15)) (justify left bottom) hide)
    )
    (property "Manufacturer" "Bourns" (at 248.92 167.64 0)
      (effects (font (size 1.27 1.27) (thickness 0.15)) (justify left bottom) hide)
    )
    (property "MPN" "CR0603-J/-000ELF" (at 248.92 165.1 0)
      (effects (font (size 1.27 1.27) (thickness 0.15)) (justify left bottom) hide)
    )
    (property "Val" "0R" (at 229.87 142.875 0)
      (effects (font (size 1.27 1.27) (thickness 0.15)) (justify left bottom))
    )
    (property "License" "Apache-2.0" (at 248.92 170.18 0)
      (effects (font (size 1.27 1.27) (thickness 0.15)) (justify left bottom) hide)
    )
    (property "Author" "Antmicro" (at 248.92 172.72 0)
      (effects (font (size 1.27 1.27) (thickness 0.15)) (justify left bottom) hide)
    )
    (property "Tolerance" "~" (at 248.92 154.94 0)
      (effects (font (size 1.27 1.27)) (justify left bottom) hide)
    )
    (property "Current" "1A" (at 248.92 175.26 0)
      (effects (font (size 1.27 1.27) (thickness 0.15)) (justify left bottom) hide)
    )
    (property "Public" "False" (at 248.92 175.26 0)
      (effects (font (size 1.27 1.27)) (justify left bottom) hide)
    )
    (pin "1")
    (pin "2")
    (instances
      (project "antmicro-hdmi-mipi-bridge-hw"
        (path ""
          (reference "R6") (unit 1)
        )
      )
    )
  )

  (symbol (lib_id "antmicropower:PWR_FLAG") (at 125.73 97.155 0) (unit 1)
    (in_bom yes) (on_board yes) (dnp no)
    (property "Reference" "#FLG0109" (at 125.73 95.25 0)
      (effects (font (size 1.27 1.27)) hide)
    )
    (property "Value" "PWR_FLAG" (at 121.285 93.345 0)
      (effects (font (size 1.27 1.27)) (justify left))
    )
    (property "Footprint" "" (at 125.73 97.155 0)
      (effects (font (size 1.27 1.27)) hide)
    )
    (property "Datasheet" "" (at 125.73 97.155 0)
      (effects (font (size 1.27 1.27)) hide)
    )
    (pin "1")
    (instances
      (project "antmicro-hdmi-mipi-bridge-hw"
        (path ""
          (reference "#FLG0109") (unit 1)
        )
      )
    )
  )

  (symbol (lib_id "antmicropower:GND") (at 219.71 170.18 0) (unit 1)
    (in_bom yes) (on_board yes) (dnp no)
    (property "Reference" "#PWR0157" (at 219.71 176.53 0)
      (effects (font (size 1.27 1.27)) hide)
    )
    (property "Value" "GND" (at 221.615 172.72 0)
      (effects (font (size 1.27 1.27) (thickness 0.15)) (justify left bottom))
    )
    (property "Footprint" "" (at 219.71 170.18 0)
      (effects (font (size 1.27 1.27) (thickness 0.15)) (justify left bottom) hide)
    )
    (property "Datasheet" "" (at 219.71 170.18 0)
      (effects (font (size 1.27 1.27) (thickness 0.15)) (justify left bottom) hide)
    )
    (property "Author" "Antmicro" (at 228.6 177.8 0)
      (effects (font (size 1.27 1.27) (thickness 0.15)) (justify left bottom) hide)
    )
    (property "License" "Apache-2.0" (at 228.6 180.34 0)
      (effects (font (size 1.27 1.27) (thickness 0.15)) (justify left bottom) hide)
    )
    (pin "1")
    (instances
      (project "antmicro-hdmi-mipi-bridge-hw"
        (path ""
          (reference "#PWR0157") (unit 1)
        )
      )
    )
  )

  (symbol (lib_id "antmicroCapacitors0603:C_10u_0603") (at 330.2 181.61 90) (unit 1)
    (in_bom yes) (on_board yes) (dnp no)
    (property "Reference" "C17" (at 327.66 177.165 90)
      (effects (font (size 1.524 1.524)) (justify left))
    )
    (property "Value" "C_10u_0603" (at 340.36 161.29 0)
      (effects (font (size 1.27 1.27) (thickness 0.15)) (justify left bottom) hide)
    )
    (property "Footprint" "antmicro-footprints:C_0603_1608Metric" (at 342.9 161.29 0)
      (effects (font (size 1.27 1.27) (thickness 0.15)) (justify left bottom) hide)
    )
    (property "Datasheet" "https://www.murata.com/products/productdetail?partno=GRM188R61A106KE69%23" (at 345.44 161.29 0)
      (effects (font (size 1.27 1.27) (thickness 0.15)) (justify left bottom) hide)
    )
    (property "Manufacturer" "Murata" (at 350.52 161.29 0)
      (effects (font (size 1.27 1.27) (thickness 0.15)) (justify left bottom) hide)
    )
    (property "MPN" "GRM188R61A106KE69D" (at 347.98 161.29 0)
      (effects (font (size 1.27 1.27) (thickness 0.15)) (justify left bottom) hide)
    )
    (property "Val" "10u" (at 327.025 179.07 90)
      (effects (font (size 1.27 1.27) (thickness 0.15)) (justify left bottom))
    )
    (property "License" "Apache-2.0" (at 353.06 161.29 0)
      (effects (font (size 1.27 1.27) (thickness 0.15)) (justify left bottom) hide)
    )
    (property "Author" "Antmicro" (at 355.6 161.29 0)
      (effects (font (size 1.27 1.27) (thickness 0.15)) (justify left bottom) hide)
    )
    (property "Voltage" "" (at 358.14 161.29 0)
      (effects (font (size 1.27 1.27)) (justify left bottom) hide)
    )
    (property "Dielectric" "template_dielectric" (at 360.68 161.29 0)
      (effects (font (size 1.27 1.27)) (justify left bottom) hide)
    )
    (property "Public" "False" (at 363.22 161.29 0)
      (effects (font (size 1.27 1.27)) (justify left bottom) hide)
    )
    (pin "1")
    (pin "2")
    (instances
      (project "antmicro-hdmi-mipi-bridge-hw"
        (path ""
          (reference "C17") (unit 1)
        )
      )
    )
  )

  (symbol (lib_id "antmicroOscillators:Oscillator_27MHz_TXC_7C") (at 337.82 38.1 0) (unit 1)
    (in_bom yes) (on_board yes) (dnp no)
    (property "Reference" "Y1" (at 347.98 31.75 0)
      (effects (font (size 1.27 1.27)))
    )
    (property "Value" "Oscillator_27MHz_TXC_7C" (at 363.22 50.165 0)
      (effects (font (size 1.27 1.27) (thickness 0.15)) (justify left bottom) hide)
    )
    (property "Footprint" "antmicro-footprints:Oscillator_SMD_TXC_7C_5x3.2x1.2mm" (at 363.22 52.705 0)
      (effects (font (size 1.27 1.27) (thickness 0.15)) (justify left bottom) hide)
    )
    (property "Datasheet" "http://www.txccorp.com/download/products/oscillators/2015TXC_7C_57.pdf" (at 363.22 55.245 0)
      (effects (font (size 1.27 1.27) (thickness 0.15)) (justify left bottom) hide)
    )
    (property "MPN" "7C-27.000MBB-T" (at 338.455 34.925 0)
      (effects (font (size 1.27 1.27) (thickness 0.15)) (justify left bottom))
    )
    (property "Manufacturer" "TXC" (at 363.22 45.085 0)
      (effects (font (size 1.27 1.27) (thickness 0.15)) (justify left bottom) hide)
    )
    (property "Author" "Antmicro" (at 363.22 57.785 0)
      (effects (font (size 1.27 1.27) (thickness 0.15)) (justify left bottom) hide)
    )
    (property "License" "Apache-2.0" (at 363.22 60.325 0)
      (effects (font (size 1.27 1.27) (thickness 0.15)) (justify left bottom) hide)
    )
    (property "Val" "27 MHz" (at 344.17 47.625 0)
      (effects (font (size 1.27 1.27) (thickness 0.15)) (justify left bottom))
    )
    (property "Public" "False" (at 369.57 62.23 0)
      (effects (font (size 1.27 1.27)) (justify left bottom) hide)
    )
    (pin "1")
    (pin "2")
    (pin "3")
    (pin "4")
    (instances
      (project "antmicro-hdmi-mipi-bridge-hw"
        (path ""
          (reference "Y1") (unit 1)
        )
      )
    )
  )

  (symbol (lib_id "antmicropower:PWR_FLAG") (at 188.595 225.425 180) (unit 1)
    (in_bom yes) (on_board yes) (dnp no)
    (property "Reference" "#FLG0112" (at 188.595 227.33 0)
      (effects (font (size 1.27 1.27)) hide)
    )
    (property "Value" "PWR_FLAG" (at 193.675 229.235 0)
      (effects (font (size 1.27 1.27)) (justify left))
    )
    (property "Footprint" "" (at 188.595 225.425 0)
      (effects (font (size 1.27 1.27)) hide)
    )
    (property "Datasheet" "" (at 188.595 225.425 0)
      (effects (font (size 1.27 1.27)) hide)
    )
    (pin "1")
    (instances
      (project "antmicro-hdmi-mipi-bridge-hw"
        (path ""
          (reference "#FLG0112") (unit 1)
        )
      )
    )
  )

  (symbol (lib_id "antmicroFerriteBeadsandChips:FB_1kZ_0.8A_WE-CBF_0805") (at 245.11 190.5 0) (unit 1)
    (in_bom yes) (on_board yes) (dnp no)
    (property "Reference" "FB2" (at 247.65 185.42 0)
      (effects (font (size 1.524 1.524)))
    )
    (property "Value" "FB_1kZ_0.8A_WE-CBF_0805" (at 260.35 198.628 0)
      (effects (font (size 1.27 1.27) (thickness 0.15)) (justify left bottom) hide)
    )
    (property "Footprint" "antmicro-footprints:FB_0805_2012Metric" (at 260.35 201.168 0)
      (effects (font (size 1.27 1.27) (thickness 0.15)) (justify left bottom) hide)
    )
    (property "Datasheet" "https://www.we-online.com/components/products/datasheet/742792096.pdf" (at 260.35 203.708 0)
      (effects (font (size 1.27 1.27) (thickness 0.15)) (justify left bottom) hide)
    )
    (property "MPN" "742792096" (at 260.35 193.04 0)
      (effects (font (size 1.27 1.27) (thickness 0.15)) (justify left bottom) hide)
    )
    (property "Manufacturer" "Würth Elektronik" (at 260.35 206.248 0)
      (effects (font (size 1.27 1.27) (thickness 0.15)) (justify left bottom) hide)
    )
    (property "Author" "Antmicro" (at 260.35 208.788 0)
      (effects (font (size 1.27 1.27) (thickness 0.15)) (justify left bottom) hide)
    )
    (property "License" "Apache-2.0" (at 260.35 211.328 0)
      (effects (font (size 1.27 1.27) (thickness 0.15)) (justify left bottom) hide)
    )
    (property "Val" "1kZ/0.8A" (at 243.84 187.96 0)
      (effects (font (size 1.27 1.27)) (justify left bottom))
    )
    (property "Current" "" (at 265.43 213.36 0)
      (effects (font (size 1.27 1.27) (thickness 0.15)) (justify left bottom) hide)
    )
    (property "Public" "False" (at 265.43 205.74 0)
      (effects (font (size 1.27 1.27)) (justify left bottom) hide)
    )
    (pin "1")
    (pin "2")
    (instances
      (project "antmicro-hdmi-mipi-bridge-hw"
        (path ""
          (reference "FB2") (unit 1)
        )
      )
    )
  )

  (symbol (lib_id "antmicropower:PWR_FLAG") (at 210.82 189.865 0) (unit 1)
    (in_bom yes) (on_board yes) (dnp no)
    (property "Reference" "#FLG0105" (at 210.82 187.96 0)
      (effects (font (size 1.27 1.27)) hide)
    )
    (property "Value" "PWR_FLAG" (at 210.82 186.055 0)
      (effects (font (size 1.27 1.27)))
    )
    (property "Footprint" "" (at 210.82 189.865 0)
      (effects (font (size 1.27 1.27)) hide)
    )
    (property "Datasheet" "" (at 210.82 189.865 0)
      (effects (font (size 1.27 1.27)) hide)
    )
    (pin "1")
    (instances
      (project "antmicro-hdmi-mipi-bridge-hw"
        (path ""
          (reference "#FLG0105") (unit 1)
        )
      )
    )
  )

  (symbol (lib_id "antmicropower:GND") (at 231.14 248.92 0) (unit 1)
    (in_bom yes) (on_board yes) (dnp no)
    (property "Reference" "#PWR0120" (at 231.14 255.27 0)
      (effects (font (size 1.27 1.27)) hide)
    )
    (property "Value" "GND" (at 229.235 254 0)
      (effects (font (size 1.27 1.27) (thickness 0.15)) (justify left bottom))
    )
    (property "Footprint" "" (at 231.14 248.92 0)
      (effects (font (size 1.27 1.27) (thickness 0.15)) (justify left bottom) hide)
    )
    (property "Datasheet" "" (at 231.14 248.92 0)
      (effects (font (size 1.27 1.27) (thickness 0.15)) (justify left bottom) hide)
    )
    (property "Author" "Antmicro" (at 240.03 256.54 0)
      (effects (font (size 1.27 1.27) (thickness 0.15)) (justify left bottom) hide)
    )
    (property "License" "Apache-2.0" (at 240.03 259.08 0)
      (effects (font (size 1.27 1.27) (thickness 0.15)) (justify left bottom) hide)
    )
    (pin "1")
    (instances
      (project "antmicro-hdmi-mipi-bridge-hw"
        (path ""
          (reference "#PWR0120") (unit 1)
        )
      )
    )
  )

  (symbol (lib_id "antmicroCapacitors0402:C_100n_0402") (at 381 91.44 90) (unit 1)
    (in_bom yes) (on_board yes) (dnp no) (fields_autoplaced)
    (property "Reference" "C22" (at 383.54 87.6236 90)
      (effects (font (size 1.524 1.524)) (justify right))
    )
    (property "Value" "C_100n_0402" (at 391.16 71.12 0)
      (effects (font (size 1.27 1.27) (thickness 0.15)) (justify left bottom) hide)
    )
    (property "Footprint" "antmicro-footprints:C_0402_1005Metric" (at 393.7 71.12 0)
      (effects (font (size 1.27 1.27) (thickness 0.15)) (justify left bottom) hide)
    )
    (property "Datasheet" "https://www.murata.com/products/productdetail?partno=GRM155R61H104KE14%23" (at 396.24 71.12 0)
      (effects (font (size 1.27 1.27) (thickness 0.15)) (justify left bottom) hide)
    )
    (property "Manufacturer" "Murata" (at 401.32 71.12 0)
      (effects (font (size 1.27 1.27) (thickness 0.15)) (justify left bottom) hide)
    )
    (property "MPN" "GRM155R61H104KE14D" (at 398.78 71.12 0)
      (effects (font (size 1.27 1.27) (thickness 0.15)) (justify left bottom) hide)
    )
    (property "Val" "100n" (at 383.54 90.1636 90)
      (effects (font (size 1.27 1.27) (thickness 0.15)) (justify right))
    )
    (property "License" "Apache-2.0" (at 403.86 71.12 0)
      (effects (font (size 1.27 1.27) (thickness 0.15)) (justify left bottom) hide)
    )
    (property "Author" "Antmicro" (at 406.4 71.12 0)
      (effects (font (size 1.27 1.27) (thickness 0.15)) (justify left bottom) hide)
    )
    (property "Voltage" "50V" (at 408.94 71.12 0)
      (effects (font (size 1.27 1.27)) (justify left bottom) hide)
    )
    (property "Dielectric" "X5R" (at 411.48 71.12 0)
      (effects (font (size 1.27 1.27)) (justify left bottom) hide)
    )
    (property "Public" "False" (at 414.02 71.12 0)
      (effects (font (size 1.27 1.27)) (justify left bottom) hide)
    )
    (pin "1")
    (pin "2")
    (instances
      (project "antmicro-hdmi-mipi-bridge-hw"
        (path ""
          (reference "C22") (unit 1)
        )
      )
    )
  )

  (symbol (lib_id "antmicroCapacitors0402:C_100n_0402") (at 219.71 152.4 90) (unit 1)
    (in_bom yes) (on_board yes) (dnp no) (fields_autoplaced)
    (property "Reference" "C28" (at 222.25 148.5836 90)
      (effects (font (size 1.524 1.524)) (justify right))
    )
    (property "Value" "C_100n_0402" (at 229.87 132.08 0)
      (effects (font (size 1.27 1.27) (thickness 0.15)) (justify left bottom) hide)
    )
    (property "Footprint" "antmicro-footprints:C_0402_1005Metric" (at 232.41 132.08 0)
      (effects (font (size 1.27 1.27) (thickness 0.15)) (justify left bottom) hide)
    )
    (property "Datasheet" "https://www.murata.com/products/productdetail?partno=GRM155R61H104KE14%23" (at 234.95 132.08 0)
      (effects (font (size 1.27 1.27) (thickness 0.15)) (justify left bottom) hide)
    )
    (property "Manufacturer" "Murata" (at 240.03 132.08 0)
      (effects (font (size 1.27 1.27) (thickness 0.15)) (justify left bottom) hide)
    )
    (property "MPN" "GRM155R61H104KE14D" (at 237.49 132.08 0)
      (effects (font (size 1.27 1.27) (thickness 0.15)) (justify left bottom) hide)
    )
    (property "Val" "100n" (at 222.25 151.1236 90)
      (effects (font (size 1.27 1.27) (thickness 0.15)) (justify right))
    )
    (property "License" "Apache-2.0" (at 242.57 132.08 0)
      (effects (font (size 1.27 1.27) (thickness 0.15)) (justify left bottom) hide)
    )
    (property "Author" "Antmicro" (at 245.11 132.08 0)
      (effects (font (size 1.27 1.27) (thickness 0.15)) (justify left bottom) hide)
    )
    (property "Voltage" "50V" (at 247.65 132.08 0)
      (effects (font (size 1.27 1.27)) (justify left bottom) hide)
    )
    (property "Dielectric" "X5R" (at 250.19 132.08 0)
      (effects (font (size 1.27 1.27)) (justify left bottom) hide)
    )
    (property "Public" "False" (at 252.73 132.08 0)
      (effects (font (size 1.27 1.27)) (justify left bottom) hide)
    )
    (pin "1")
    (pin "2")
    (instances
      (project "antmicro-hdmi-mipi-bridge-hw"
        (path ""
          (reference "C28") (unit 1)
        )
      )
    )
  )

  (symbol (lib_id "antmicropower:PWR_FLAG") (at 210.82 220.345 0) (unit 1)
    (in_bom yes) (on_board yes) (dnp no)
    (property "Reference" "#FLG0106" (at 210.82 218.44 0)
      (effects (font (size 1.27 1.27)) hide)
    )
    (property "Value" "PWR_FLAG" (at 210.82 216.535 0)
      (effects (font (size 1.27 1.27)))
    )
    (property "Footprint" "" (at 210.82 220.345 0)
      (effects (font (size 1.27 1.27)) hide)
    )
    (property "Datasheet" "" (at 210.82 220.345 0)
      (effects (font (size 1.27 1.27)) hide)
    )
    (pin "1")
    (instances
      (project "antmicro-hdmi-mipi-bridge-hw"
        (path ""
          (reference "#FLG0106") (unit 1)
        )
      )
    )
  )

  (symbol (lib_id "antmicropower:GND") (at 231.14 200.66 0) (unit 1)
    (in_bom yes) (on_board yes) (dnp no)
    (property "Reference" "#PWR0107" (at 231.14 207.01 0)
      (effects (font (size 1.27 1.27)) hide)
    )
    (property "Value" "GND" (at 233.045 203.2 0)
      (effects (font (size 1.27 1.27) (thickness 0.15)) (justify left bottom))
    )
    (property "Footprint" "" (at 231.14 200.66 0)
      (effects (font (size 1.27 1.27) (thickness 0.15)) (justify left bottom) hide)
    )
    (property "Datasheet" "" (at 231.14 200.66 0)
      (effects (font (size 1.27 1.27) (thickness 0.15)) (justify left bottom) hide)
    )
    (property "Author" "Antmicro" (at 240.03 208.28 0)
      (effects (font (size 1.27 1.27) (thickness 0.15)) (justify left bottom) hide)
    )
    (property "License" "Apache-2.0" (at 240.03 210.82 0)
      (effects (font (size 1.27 1.27) (thickness 0.15)) (justify left bottom) hide)
    )
    (pin "1")
    (instances
      (project "antmicro-hdmi-mipi-bridge-hw"
        (path ""
          (reference "#PWR0107") (unit 1)
        )
      )
    )
  )

  (symbol (lib_id "antmicropower:GND") (at 219.71 200.66 0) (unit 1)
    (in_bom yes) (on_board yes) (dnp no)
    (property "Reference" "#PWR0106" (at 219.71 207.01 0)
      (effects (font (size 1.27 1.27)) hide)
    )
    (property "Value" "GND" (at 221.615 203.2 0)
      (effects (font (size 1.27 1.27) (thickness 0.15)) (justify left bottom))
    )
    (property "Footprint" "" (at 219.71 200.66 0)
      (effects (font (size 1.27 1.27) (thickness 0.15)) (justify left bottom) hide)
    )
    (property "Datasheet" "" (at 219.71 200.66 0)
      (effects (font (size 1.27 1.27) (thickness 0.15)) (justify left bottom) hide)
    )
    (property "Author" "Antmicro" (at 228.6 208.28 0)
      (effects (font (size 1.27 1.27) (thickness 0.15)) (justify left bottom) hide)
    )
    (property "License" "Apache-2.0" (at 228.6 210.82 0)
      (effects (font (size 1.27 1.27) (thickness 0.15)) (justify left bottom) hide)
    )
    (pin "1")
    (instances
      (project "antmicro-hdmi-mipi-bridge-hw"
        (path ""
          (reference "#PWR0106") (unit 1)
        )
      )
    )
  )

  (symbol (lib_id "antmicroFerriteBeadsandChips:FB_120Z_3A_Murata-BLM18SG_0603") (at 76.2 87.63 90) (unit 1)
    (in_bom yes) (on_board yes) (dnp no)
    (property "Reference" "FB1" (at 78.74 82.55 90)
      (effects (font (size 1.524 1.524)))
    )
    (property "Value" "FB_120Z_3A_Murata-BLM18SG_0603" (at 78.74 73.66 90)
      (effects (font (size 1.27 1.27) (thickness 0.15)) (justify left bottom) hide)
    )
    (property "Footprint" "antmicro-footprints:FB_0603_1608Metric" (at 83.82 73.66 0)
      (effects (font (size 1.27 1.27) (thickness 0.15)) (justify left bottom) hide)
    )
    (property "Datasheet" "https://www.murata.com/products/productdata/8796738650142/ENFA0003.pdf?1681308024000" (at 86.36 73.66 0)
      (effects (font (size 1.27 1.27) (thickness 0.15)) (justify left bottom) hide)
    )
    (property "MPN" "BLM18SG121TN1D" (at 88.9 73.66 0)
      (effects (font (size 1.27 1.27) (thickness 0.15)) (justify left bottom) hide)
    )
    (property "Manufacturer" "Murata" (at 91.44 73.66 0)
      (effects (font (size 1.27 1.27) (thickness 0.15)) (justify left bottom) hide)
    )
    (property "Author" "Antmicro" (at 93.98 73.66 0)
      (effects (font (size 1.27 1.27) (thickness 0.15)) (justify left bottom) hide)
    )
    (property "License" "Apache-2.0" (at 96.52 73.66 0)
      (effects (font (size 1.27 1.27) (thickness 0.15)) (justify left bottom) hide)
    )
    (property "Val" "120Z/3A" (at 85.09 87.63 90)
      (effects (font (size 1.27 1.27)) (justify left bottom))
    )
    (property "Current" "" (at 99.06 67.31 0)
      (effects (font (size 1.27 1.27) (thickness 0.15)) (justify left bottom) hide)
    )
    (property "Public" "False" (at 91.44 67.31 0)
      (effects (font (size 1.27 1.27)) (justify left bottom) hide)
    )
    (pin "1")
    (pin "2")
    (instances
      (project "antmicro-hdmi-mipi-bridge-hw"
        (path ""
          (reference "FB1") (unit 1)
        )
      )
    )
  )

  (symbol (lib_id "antmicroCapacitors0402:C_47p_0402") (at 364.49 45.72 90) (unit 1)
    (in_bom yes) (on_board yes) (dnp no)
    (property "Reference" "C21" (at 370.84 41.275 90)
      (effects (font (size 1.524 1.524)) (justify left))
    )
    (property "Value" "C_47p_0402" (at 374.65 25.4 0)
      (effects (font (size 1.27 1.27) (thickness 0.15)) (justify left bottom) hide)
    )
    (property "Footprint" "antmicro-footprints:C_0402_1005Metric" (at 377.19 25.4 0)
      (effects (font (size 1.27 1.27) (thickness 0.15)) (justify left bottom) hide)
    )
    (property "Datasheet" "https://www.kemet.com/en/us/capacitors/product/C0402C470J5GACTU.html" (at 379.73 25.4 0)
      (effects (font (size 1.27 1.27) (thickness 0.15)) (justify left bottom) hide)
    )
    (property "Manufacturer" "KEMET" (at 384.81 25.4 0)
      (effects (font (size 1.27 1.27) (thickness 0.15)) (justify left bottom) hide)
    )
    (property "MPN" "C0402C470J5GACTU" (at 382.27 25.4 0)
      (effects (font (size 1.27 1.27) (thickness 0.15)) (justify left bottom) hide)
    )
    (property "Val" "47p" (at 370.84 42.545 90)
      (effects (font (size 1.27 1.27) (thickness 0.15)) (justify left bottom))
    )
    (property "License" "Apache-2.0" (at 387.35 25.4 0)
      (effects (font (size 1.27 1.27) (thickness 0.15)) (justify left bottom) hide)
    )
    (property "Author" "Antmicro" (at 389.89 25.4 0)
      (effects (font (size 1.27 1.27) (thickness 0.15)) (justify left bottom) hide)
    )
    (property "Voltage" "" (at 392.43 25.4 0)
      (effects (font (size 1.27 1.27)) (justify left bottom) hide)
    )
    (property "Dielectric" "C0G" (at 394.97 25.4 0)
      (effects (font (size 1.27 1.27)) (justify left bottom) hide)
    )
    (property "Public" "False" (at 397.51 25.4 0)
      (effects (font (size 1.27 1.27)) (justify left bottom) hide)
    )
    (pin "1")
    (pin "2")
    (instances
      (project "antmicro-hdmi-mipi-bridge-hw"
        (path ""
          (reference "C21") (unit 1)
        )
      )
    )
  )

  (symbol (lib_id "antmicropower:GND") (at 85.09 261.62 0) (unit 1)
    (in_bom yes) (on_board yes) (dnp no)
    (property "Reference" "#PWR0139" (at 85.09 267.97 0)
      (effects (font (size 1.27 1.27)) hide)
    )
    (property "Value" "GND" (at 83.185 266.7 0)
      (effects (font (size 1.27 1.27) (thickness 0.15)) (justify left bottom))
    )
    (property "Footprint" "" (at 85.09 261.62 0)
      (effects (font (size 1.27 1.27) (thickness 0.15)) (justify left bottom) hide)
    )
    (property "Datasheet" "" (at 85.09 261.62 0)
      (effects (font (size 1.27 1.27) (thickness 0.15)) (justify left bottom) hide)
    )
    (property "Author" "Antmicro" (at 93.98 269.24 0)
      (effects (font (size 1.27 1.27) (thickness 0.15)) (justify left bottom) hide)
    )
    (property "License" "Apache-2.0" (at 93.98 271.78 0)
      (effects (font (size 1.27 1.27) (thickness 0.15)) (justify left bottom) hide)
    )
    (pin "1")
    (instances
      (project "antmicro-hdmi-mipi-bridge-hw"
        (path ""
          (reference "#PWR0139") (unit 1)
        )
      )
    )
  )

  (symbol (lib_id "antmicropower:GND") (at 332.74 107.315 0) (mirror y) (unit 1)
    (in_bom yes) (on_board yes) (dnp no)
    (property "Reference" "#PWR0115" (at 332.74 113.665 0)
      (effects (font (size 1.27 1.27)) hide)
    )
    (property "Value" "GND" (at 334.645 111.76 0)
      (effects (font (size 1.27 1.27) (thickness 0.15)) (justify left bottom))
    )
    (property "Footprint" "" (at 332.74 107.315 0)
      (effects (font (size 1.27 1.27) (thickness 0.15)) (justify left bottom) hide)
    )
    (property "Datasheet" "" (at 332.74 107.315 0)
      (effects (font (size 1.27 1.27) (thickness 0.15)) (justify left bottom) hide)
    )
    (property "Author" "Antmicro" (at 323.85 114.935 0)
      (effects (font (size 1.27 1.27) (thickness 0.15)) (justify left bottom) hide)
    )
    (property "License" "Apache-2.0" (at 323.85 117.475 0)
      (effects (font (size 1.27 1.27) (thickness 0.15)) (justify left bottom) hide)
    )
    (pin "1")
    (instances
      (project "antmicro-hdmi-mipi-bridge-hw"
        (path ""
          (reference "#PWR0115") (unit 1)
        )
      )
    )
  )

  (symbol (lib_id "antmicroResistors0402:R_22R_0402") (at 370.84 38.1 0) (unit 1)
    (in_bom yes) (on_board yes) (dnp no)
    (property "Reference" "R13" (at 373.38 33.655 0)
      (effects (font (size 1.524 1.524)))
    )
    (property "Value" "R_22R_0402" (at 391.16 50.8 0)
      (effects (font (size 1.27 1.27) (thickness 0.15)) (justify left bottom) hide)
    )
    (property "Footprint" "antmicro-footprints:R_0402_1005Metric" (at 391.16 53.34 0)
      (effects (font (size 1.27 1.27) (thickness 0.15)) (justify left bottom) hide)
    )
    (property "Datasheet" "https://www.bourns.com/docs/product-datasheets/cr.pdf" (at 391.16 55.88 0)
      (effects (font (size 1.27 1.27) (thickness 0.15)) (justify left bottom) hide)
    )
    (property "Manufacturer" "Bourns" (at 391.16 60.96 0)
      (effects (font (size 1.27 1.27) (thickness 0.15)) (justify left bottom) hide)
    )
    (property "MPN" "CR0402-FX-22R0GLF" (at 391.16 58.42 0)
      (effects (font (size 1.27 1.27) (thickness 0.15)) (justify left bottom) hide)
    )
    (property "Val" "22R" (at 371.475 36.195 0)
      (effects (font (size 1.27 1.27) (thickness 0.15)) (justify left bottom))
    )
    (property "License" "Apache-2.0" (at 391.16 63.5 0)
      (effects (font (size 1.27 1.27) (thickness 0.15)) (justify left bottom) hide)
    )
    (property "Author" "Antmicro" (at 391.16 66.04 0)
      (effects (font (size 1.27 1.27) (thickness 0.15)) (justify left bottom) hide)
    )
    (property "Tolerance" "1%" (at 391.16 48.26 0)
      (effects (font (size 1.27 1.27)) (justify left bottom) hide)
    )
    (property "Public" "False" (at 391.16 68.58 0)
      (effects (font (size 1.27 1.27)) (justify left bottom) hide)
    )
    (pin "1")
    (pin "2")
    (instances
      (project "antmicro-hdmi-mipi-bridge-hw"
        (path ""
          (reference "R13") (unit 1)
        )
      )
    )
  )

  (symbol (lib_id "antmicropower:GND") (at 292.1 48.26 0) (unit 1)
    (in_bom yes) (on_board yes) (dnp no)
    (property "Reference" "#PWR0125" (at 292.1 54.61 0)
      (effects (font (size 1.27 1.27)) hide)
    )
    (property "Value" "GND" (at 290.195 52.705 0)
      (effects (font (size 1.27 1.27) (thickness 0.15)) (justify left bottom))
    )
    (property "Footprint" "" (at 292.1 48.26 0)
      (effects (font (size 1.27 1.27) (thickness 0.15)) (justify left bottom) hide)
    )
    (property "Datasheet" "" (at 292.1 48.26 0)
      (effects (font (size 1.27 1.27) (thickness 0.15)) (justify left bottom) hide)
    )
    (property "Author" "Antmicro" (at 300.99 55.88 0)
      (effects (font (size 1.27 1.27) (thickness 0.15)) (justify left bottom) hide)
    )
    (property "License" "Apache-2.0" (at 300.99 58.42 0)
      (effects (font (size 1.27 1.27) (thickness 0.15)) (justify left bottom) hide)
    )
    (pin "1")
    (instances
      (project "antmicro-hdmi-mipi-bridge-hw"
        (path ""
          (reference "#PWR0125") (unit 1)
        )
      )
    )
  )

  (symbol (lib_id "antmicroFerriteBeadsandChips:FB_1kZ_0.8A_WE-CBF_0805") (at 245.11 205.74 0) (unit 1)
    (in_bom yes) (on_board yes) (dnp no)
    (property "Reference" "FB3" (at 247.65 200.66 0)
      (effects (font (size 1.524 1.524)))
    )
    (property "Value" "FB_1kZ_0.8A_WE-CBF_0805" (at 260.35 213.868 0)
      (effects (font (size 1.27 1.27) (thickness 0.15)) (justify left bottom) hide)
    )
    (property "Footprint" "antmicro-footprints:FB_0805_2012Metric" (at 260.35 216.408 0)
      (effects (font (size 1.27 1.27) (thickness 0.15)) (justify left bottom) hide)
    )
    (property "Datasheet" "https://www.we-online.com/components/products/datasheet/742792096.pdf" (at 260.35 218.948 0)
      (effects (font (size 1.27 1.27) (thickness 0.15)) (justify left bottom) hide)
    )
    (property "MPN" "742792096" (at 260.35 208.28 0)
      (effects (font (size 1.27 1.27) (thickness 0.15)) (justify left bottom) hide)
    )
    (property "Manufacturer" "Würth Elektronik" (at 260.35 221.488 0)
      (effects (font (size 1.27 1.27) (thickness 0.15)) (justify left bottom) hide)
    )
    (property "Author" "Antmicro" (at 260.35 224.028 0)
      (effects (font (size 1.27 1.27) (thickness 0.15)) (justify left bottom) hide)
    )
    (property "License" "Apache-2.0" (at 260.35 226.568 0)
      (effects (font (size 1.27 1.27) (thickness 0.15)) (justify left bottom) hide)
    )
    (property "Val" "1kZ/0.8A" (at 243.84 203.2 0)
      (effects (font (size 1.27 1.27)) (justify left bottom))
    )
    (property "Current" "" (at 265.43 228.6 0)
      (effects (font (size 1.27 1.27) (thickness 0.15)) (justify left bottom) hide)
    )
    (property "Public" "False" (at 265.43 220.98 0)
      (effects (font (size 1.27 1.27)) (justify left bottom) hide)
    )
    (pin "1")
    (pin "2")
    (instances
      (project "antmicro-hdmi-mipi-bridge-hw"
        (path ""
          (reference "FB3") (unit 1)
        )
      )
    )
  )

  (symbol (lib_id "antmicroFerriteBeadsandChips:FB_600Z_0.5A_Murata-BLM18AG_0603") (at 307.34 38.1 0) (unit 1)
    (in_bom yes) (on_board yes) (dnp no)
    (property "Reference" "FB6" (at 310.515 32.385 0)
      (effects (font (size 1.524 1.524)))
    )
    (property "Value" "FB_600Z_0.5A_Murata-BLM18AG_0603" (at 322.58 40.64 0)
      (effects (font (size 1.27 1.27) (thickness 0.15)) (justify left bottom) hide)
    )
    (property "Footprint" "antmicro-footprints:FB_0603_1608Metric" (at 322.58 45.72 0)
      (effects (font (size 1.27 1.27) (thickness 0.15)) (justify left bottom) hide)
    )
    (property "Datasheet" "https://www.murata.com/en-us/products/productdata/8796738650142/ENFA0003.pdf" (at 322.58 48.26 0)
      (effects (font (size 1.27 1.27) (thickness 0.15)) (justify left bottom) hide)
    )
    (property "MPN" "BLM18AG601SN1D" (at 322.58 50.8 0)
      (effects (font (size 1.27 1.27) (thickness 0.15)) (justify left bottom) hide)
    )
    (property "Manufacturer" "Murata" (at 322.58 53.34 0)
      (effects (font (size 1.27 1.27) (thickness 0.15)) (justify left bottom) hide)
    )
    (property "Author" "Antmicro" (at 322.58 55.88 0)
      (effects (font (size 1.27 1.27) (thickness 0.15)) (justify left bottom) hide)
    )
    (property "License" "Apache-2.0" (at 322.58 58.42 0)
      (effects (font (size 1.27 1.27) (thickness 0.15)) (justify left bottom) hide)
    )
    (property "Val" "600Z/0.5A" (at 305.435 35.56 0)
      (effects (font (size 1.27 1.27)) (justify left bottom))
    )
    (property "Current" "" (at 327.66 60.96 0)
      (effects (font (size 1.27 1.27) (thickness 0.15)) (justify left bottom) hide)
    )
    (property "Public" "False" (at 327.66 53.34 0)
      (effects (font (size 1.27 1.27)) (justify left bottom) hide)
    )
    (pin "1")
    (pin "2")
    (instances
      (project "antmicro-hdmi-mipi-bridge-hw"
        (path ""
          (reference "FB6") (unit 1)
        )
      )
    )
  )

  (symbol (lib_id "antmicropower:PWR_FLAG") (at 210.82 174.625 0) (unit 1)
    (in_bom yes) (on_board yes) (dnp no)
    (property "Reference" "#FLG0101" (at 210.82 172.72 0)
      (effects (font (size 1.27 1.27)) hide)
    )
    (property "Value" "PWR_FLAG" (at 210.82 170.815 0)
      (effects (font (size 1.27 1.27)))
    )
    (property "Footprint" "" (at 210.82 174.625 0)
      (effects (font (size 1.27 1.27)) hide)
    )
    (property "Datasheet" "" (at 210.82 174.625 0)
      (effects (font (size 1.27 1.27)) hide)
    )
    (pin "1")
    (instances
      (project "antmicro-hdmi-mipi-bridge-hw"
        (path ""
          (reference "#FLG0101") (unit 1)
        )
      )
    )
  )

  (symbol (lib_id "antmicroCapacitors0603:C_4u7_0603") (at 231.14 246.38 90) (unit 1)
    (in_bom yes) (on_board yes) (dnp no) (fields_autoplaced)
    (property "Reference" "C11" (at 233.68 242.5636 90)
      (effects (font (size 1.524 1.524)) (justify right))
    )
    (property "Value" "C_4u7_0603" (at 241.3 226.06 0)
      (effects (font (size 1.27 1.27) (thickness 0.15)) (justify left bottom) hide)
    )
    (property "Footprint" "antmicro-footprints:C_0603_1608Metric" (at 243.84 226.06 0)
      (effects (font (size 1.27 1.27) (thickness 0.15)) (justify left bottom) hide)
    )
    (property "Datasheet" "https://product.tdk.com/en/search/capacitor/ceramic/mlcc/info?part_no=C1608X5R1V475M080AC" (at 246.38 226.06 0)
      (effects (font (size 1.27 1.27) (thickness 0.15)) (justify left bottom) hide)
    )
    (property "Manufacturer" "TDK" (at 251.46 226.06 0)
      (effects (font (size 1.27 1.27) (thickness 0.15)) (justify left bottom) hide)
    )
    (property "MPN" "C1608X5R1V475M080AC" (at 248.92 226.06 0)
      (effects (font (size 1.27 1.27) (thickness 0.15)) (justify left bottom) hide)
    )
    (property "Val" "4u7" (at 233.68 245.1036 90)
      (effects (font (size 1.27 1.27) (thickness 0.15)) (justify right))
    )
    (property "License" "Apache-2.0" (at 254 226.06 0)
      (effects (font (size 1.27 1.27) (thickness 0.15)) (justify left bottom) hide)
    )
    (property "Author" "Antmicro" (at 256.54 226.06 0)
      (effects (font (size 1.27 1.27) (thickness 0.15)) (justify left bottom) hide)
    )
    (property "Voltage" "" (at 259.08 226.06 0)
      (effects (font (size 1.27 1.27)) (justify left bottom) hide)
    )
    (property "Dielectric" "" (at 261.62 226.06 0)
      (effects (font (size 1.27 1.27)) (justify left bottom) hide)
    )
    (property "Public" "False" (at 264.16 226.06 0)
      (effects (font (size 1.27 1.27)) (justify left bottom) hide)
    )
    (pin "1")
    (pin "2")
    (instances
      (project "antmicro-hdmi-mipi-bridge-hw"
        (path ""
          (reference "C11") (unit 1)
        )
      )
    )
  )

  (symbol (lib_id "antmicropower:GND") (at 307.34 93.98 0) (mirror y) (unit 1)
    (in_bom yes) (on_board yes) (dnp no)
    (property "Reference" "#PWR0114" (at 307.34 100.33 0)
      (effects (font (size 1.27 1.27)) hide)
    )
    (property "Value" "GND" (at 311.15 95.25 0)
      (effects (font (size 1.27 1.27) (thickness 0.15)) (justify left bottom))
    )
    (property "Footprint" "" (at 307.34 93.98 0)
      (effects (font (size 1.27 1.27) (thickness 0.15)) (justify left bottom) hide)
    )
    (property "Datasheet" "" (at 307.34 93.98 0)
      (effects (font (size 1.27 1.27) (thickness 0.15)) (justify left bottom) hide)
    )
    (property "Author" "Antmicro" (at 298.45 101.6 0)
      (effects (font (size 1.27 1.27) (thickness 0.15)) (justify left bottom) hide)
    )
    (property "License" "Apache-2.0" (at 298.45 104.14 0)
      (effects (font (size 1.27 1.27) (thickness 0.15)) (justify left bottom) hide)
    )
    (pin "1")
    (instances
      (project "antmicro-hdmi-mipi-bridge-hw"
        (path ""
          (reference "#PWR0114") (unit 1)
        )
      )
    )
  )

  (symbol (lib_id "antmicroCapacitors0402:C_100n_0402") (at 219.71 167.64 90) (unit 1)
    (in_bom yes) (on_board yes) (dnp no) (fields_autoplaced)
    (property "Reference" "C29" (at 222.25 163.8236 90)
      (effects (font (size 1.524 1.524)) (justify right))
    )
    (property "Value" "C_100n_0402" (at 229.87 147.32 0)
      (effects (font (size 1.27 1.27) (thickness 0.15)) (justify left bottom) hide)
    )
    (property "Footprint" "antmicro-footprints:C_0402_1005Metric" (at 232.41 147.32 0)
      (effects (font (size 1.27 1.27) (thickness 0.15)) (justify left bottom) hide)
    )
    (property "Datasheet" "https://www.murata.com/products/productdetail?partno=GRM155R61H104KE14%23" (at 234.95 147.32 0)
      (effects (font (size 1.27 1.27) (thickness 0.15)) (justify left bottom) hide)
    )
    (property "Manufacturer" "Murata" (at 240.03 147.32 0)
      (effects (font (size 1.27 1.27) (thickness 0.15)) (justify left bottom) hide)
    )
    (property "MPN" "GRM155R61H104KE14D" (at 237.49 147.32 0)
      (effects (font (size 1.27 1.27) (thickness 0.15)) (justify left bottom) hide)
    )
    (property "Val" "100n" (at 222.25 166.3636 90)
      (effects (font (size 1.27 1.27) (thickness 0.15)) (justify right))
    )
    (property "License" "Apache-2.0" (at 242.57 147.32 0)
      (effects (font (size 1.27 1.27) (thickness 0.15)) (justify left bottom) hide)
    )
    (property "Author" "Antmicro" (at 245.11 147.32 0)
      (effects (font (size 1.27 1.27) (thickness 0.15)) (justify left bottom) hide)
    )
    (property "Voltage" "50V" (at 247.65 147.32 0)
      (effects (font (size 1.27 1.27)) (justify left bottom) hide)
    )
    (property "Dielectric" "X5R" (at 250.19 147.32 0)
      (effects (font (size 1.27 1.27)) (justify left bottom) hide)
    )
    (property "Public" "False" (at 252.73 147.32 0)
      (effects (font (size 1.27 1.27)) (justify left bottom) hide)
    )
    (pin "1")
    (pin "2")
    (instances
      (project "antmicro-hdmi-mipi-bridge-hw"
        (path ""
          (reference "C29") (unit 1)
        )
      )
    )
  )

  (symbol (lib_id "antmicropower:PWR_FLAG") (at 330.835 37.465 0) (unit 1)
    (in_bom yes) (on_board yes) (dnp no)
    (property "Reference" "#FLG0113" (at 330.835 35.56 0)
      (effects (font (size 1.27 1.27)) hide)
    )
    (property "Value" "PWR_FLAG" (at 325.755 33.655 0)
      (effects (font (size 1.27 1.27)) (justify left))
    )
    (property "Footprint" "" (at 330.835 37.465 0)
      (effects (font (size 1.27 1.27)) hide)
    )
    (property "Datasheet" "" (at 330.835 37.465 0)
      (effects (font (size 1.27 1.27)) hide)
    )
    (pin "1")
    (instances
      (project "antmicro-hdmi-mipi-bridge-hw"
        (path ""
          (reference "#FLG0113") (unit 1)
        )
      )
    )
  )

  (symbol (lib_id "antmicroCapacitors0402:C_100n_0402") (at 292.1 45.72 90) (unit 1)
    (in_bom yes) (on_board yes) (dnp no)
    (property "Reference" "C12" (at 292.735 41.275 90)
      (effects (font (size 1.524 1.524)) (justify right))
    )
    (property "Value" "C_100n_0402" (at 302.26 25.4 0)
      (effects (font (size 1.27 1.27) (thickness 0.15)) (justify left bottom) hide)
    )
    (property "Footprint" "antmicro-footprints:C_0402_1005Metric" (at 304.8 25.4 0)
      (effects (font (size 1.27 1.27) (thickness 0.15)) (justify left bottom) hide)
    )
    (property "Datasheet" "https://www.murata.com/products/productdetail?partno=GRM155R61H104KE14%23" (at 307.34 25.4 0)
      (effects (font (size 1.27 1.27) (thickness 0.15)) (justify left bottom) hide)
    )
    (property "Manufacturer" "Murata" (at 312.42 25.4 0)
      (effects (font (size 1.27 1.27) (thickness 0.15)) (justify left bottom) hide)
    )
    (property "MPN" "GRM155R61H104KE14D" (at 309.88 25.4 0)
      (effects (font (size 1.27 1.27) (thickness 0.15)) (justify left bottom) hide)
    )
    (property "Val" "100n" (at 299.085 42.545 90)
      (effects (font (size 1.27 1.27) (thickness 0.15)) (justify left bottom))
    )
    (property "License" "Apache-2.0" (at 314.96 25.4 0)
      (effects (font (size 1.27 1.27) (thickness 0.15)) (justify left bottom) hide)
    )
    (property "Author" "Antmicro" (at 317.5 25.4 0)
      (effects (font (size 1.27 1.27) (thickness 0.15)) (justify left bottom) hide)
    )
    (property "Voltage" "50V" (at 320.04 25.4 0)
      (effects (font (size 1.27 1.27)) (justify left bottom) hide)
    )
    (property "Dielectric" "X5R" (at 322.58 25.4 0)
      (effects (font (size 1.27 1.27)) (justify left bottom) hide)
    )
    (property "Public" "False" (at 325.12 25.4 0)
      (effects (font (size 1.27 1.27)) (justify left bottom) hide)
    )
    (pin "1")
    (pin "2")
    (instances
      (project "antmicro-hdmi-mipi-bridge-hw"
        (path ""
          (reference "C12") (unit 1)
        )
      )
    )
  )

  (symbol (lib_id "antmicroTestPoints:TP_0.75mm_SMD") (at 92.71 200.66 0) (unit 1)
    (in_bom no) (on_board yes) (dnp no) (fields_autoplaced)
    (property "Reference" "TP1" (at 97.79 200.6599 0)
      (effects (font (size 1.27 1.27)) (justify left))
    )
    (property "Value" "TP_0.75mm_SMD" (at 107.95 208.28 0)
      (effects (font (size 1.27 1.27) (thickness 0.15)) (justify left bottom) hide)
    )
    (property "Footprint" "antmicro-footprints:TP_SMD_0.75mm" (at 107.95 210.82 0)
      (effects (font (size 1.27 1.27) (thickness 0.15)) (justify left bottom) hide)
    )
    (property "Datasheet" "" (at 107.95 213.36 0)
      (effects (font (size 1.27 1.27) (thickness 0.15)) (justify left bottom) hide)
    )
    (property "MPN" "" (at 92.71 200.66 0)
      (effects (font (size 1.27 1.27) (thickness 0.15)) (justify left bottom) hide)
    )
    (property "Manufacturer" "" (at 92.71 200.66 0)
      (effects (font (size 1.27 1.27) (thickness 0.15)) (justify left bottom) hide)
    )
    (property "Author" "Antmicro" (at 107.95 215.9 0)
      (effects (font (size 1.27 1.27) (thickness 0.15)) (justify left bottom) hide)
    )
    (property "License" "Apache-2.0" (at 107.95 218.44 0)
      (effects (font (size 1.27 1.27) (thickness 0.15)) (justify left bottom) hide)
    )
    (property "Public" "False" (at 102.87 214.63 0)
      (effects (font (size 1.27 1.27)) (justify left bottom) hide)
    )
    (pin "1")
    (instances
      (project "antmicro-hdmi-mipi-bridge-hw"
        (path ""
          (reference "TP1") (unit 1)
        )
      )
    )
  )

  (symbol (lib_id "antmicropower:GND") (at 152.4 223.52 0) (unit 1)
    (in_bom yes) (on_board yes) (dnp no)
    (property "Reference" "#PWR0136" (at 152.4 229.87 0)
      (effects (font (size 1.27 1.27)) hide)
    )
    (property "Value" "GND" (at 150.495 227.965 0)
      (effects (font (size 1.27 1.27) (thickness 0.15)) (justify left bottom))
    )
    (property "Footprint" "" (at 152.4 223.52 0)
      (effects (font (size 1.27 1.27) (thickness 0.15)) (justify left bottom) hide)
    )
    (property "Datasheet" "" (at 152.4 223.52 0)
      (effects (font (size 1.27 1.27) (thickness 0.15)) (justify left bottom) hide)
    )
    (property "Author" "Antmicro" (at 161.29 231.14 0)
      (effects (font (size 1.27 1.27) (thickness 0.15)) (justify left bottom) hide)
    )
    (property "License" "Apache-2.0" (at 161.29 233.68 0)
      (effects (font (size 1.27 1.27) (thickness 0.15)) (justify left bottom) hide)
    )
    (pin "1")
    (instances
      (project "antmicro-hdmi-mipi-bridge-hw"
        (path ""
          (reference "#PWR0136") (unit 1)
        )
      )
    )
  )

  (symbol (lib_id "antmicropower:+3V3") (at 236.22 143.51 0) (unit 1)
    (in_bom yes) (on_board yes) (dnp no) (fields_autoplaced)
    (property "Reference" "#PWR0104" (at 236.22 147.32 0)
      (effects (font (size 1.27 1.27)) hide)
    )
    (property "Value" "+3V3" (at 236.22 138.43 0)
      (effects (font (size 1.27 1.27) (thickness 0.15)) (justify left bottom))
    )
    (property "Footprint" "" (at 236.22 143.51 0)
      (effects (font (size 1.27 1.27) (thickness 0.15)) (justify left bottom) hide)
    )
    (property "Datasheet" "" (at 236.22 143.51 0)
      (effects (font (size 1.27 1.27) (thickness 0.15)) (justify left bottom) hide)
    )
    (property "Author" "Antmicro" (at 251.46 146.05 0)
      (effects (font (size 1.27 1.27) (thickness 0.15)) (justify left bottom) hide)
    )
    (property "License" "Apache-2.0" (at 251.46 148.59 0)
      (effects (font (size 1.27 1.27) (thickness 0.15)) (justify left bottom) hide)
    )
    (pin "1")
    (instances
      (project "antmicro-hdmi-mipi-bridge-hw"
        (path ""
          (reference "#PWR0104") (unit 1)
        )
      )
    )
  )

  (symbol (lib_id "antmicroCapacitors0402:C_100n_0402") (at 93.98 259.08 90) (unit 1)
    (in_bom yes) (on_board yes) (dnp no)
    (property "Reference" "C2" (at 90.805 255.27 90)
      (effects (font (size 1.524 1.524)) (justify left))
    )
    (property "Value" "C_100n_0402" (at 104.14 238.76 0)
      (effects (font (size 1.27 1.27) (thickness 0.15)) (justify left bottom) hide)
    )
    (property "Footprint" "antmicro-footprints:C_0402_1005Metric" (at 106.68 238.76 0)
      (effects (font (size 1.27 1.27) (thickness 0.15)) (justify left bottom) hide)
    )
    (property "Datasheet" "https://www.murata.com/products/productdetail?partno=GRM155R61H104KE14%23" (at 109.22 238.76 0)
      (effects (font (size 1.27 1.27) (thickness 0.15)) (justify left bottom) hide)
    )
    (property "Manufacturer" "Murata" (at 114.3 238.76 0)
      (effects (font (size 1.27 1.27) (thickness 0.15)) (justify left bottom) hide)
    )
    (property "MPN" "GRM155R61H104KE14D" (at 111.76 238.76 0)
      (effects (font (size 1.27 1.27) (thickness 0.15)) (justify left bottom) hide)
    )
    (property "Val" "100n" (at 92.075 257.81 90)
      (effects (font (size 1.27 1.27) (thickness 0.15)) (justify left bottom))
    )
    (property "License" "Apache-2.0" (at 116.84 238.76 0)
      (effects (font (size 1.27 1.27) (thickness 0.15)) (justify left bottom) hide)
    )
    (property "Author" "Antmicro" (at 119.38 238.76 0)
      (effects (font (size 1.27 1.27) (thickness 0.15)) (justify left bottom) hide)
    )
    (property "Voltage" "50V" (at 121.92 238.76 0)
      (effects (font (size 1.27 1.27)) (justify left bottom) hide)
    )
    (property "Dielectric" "X5R" (at 124.46 238.76 0)
      (effects (font (size 1.27 1.27)) (justify left bottom) hide)
    )
    (property "Public" "False" (at 127 238.76 0)
      (effects (font (size 1.27 1.27)) (justify left bottom) hide)
    )
    (pin "1")
    (pin "2")
    (instances
      (project "antmicro-hdmi-mipi-bridge-hw"
        (path ""
          (reference "C2") (unit 1)
        )
      )
    )
  )

  (symbol (lib_id "antmicropower:GND") (at 219.71 248.92 0) (unit 1)
    (in_bom yes) (on_board yes) (dnp no)
    (property "Reference" "#PWR0119" (at 219.71 255.27 0)
      (effects (font (size 1.27 1.27)) hide)
    )
    (property "Value" "GND" (at 217.805 254 0)
      (effects (font (size 1.27 1.27) (thickness 0.15)) (justify left bottom))
    )
    (property "Footprint" "" (at 219.71 248.92 0)
      (effects (font (size 1.27 1.27) (thickness 0.15)) (justify left bottom) hide)
    )
    (property "Datasheet" "" (at 219.71 248.92 0)
      (effects (font (size 1.27 1.27) (thickness 0.15)) (justify left bottom) hide)
    )
    (property "Author" "Antmicro" (at 228.6 256.54 0)
      (effects (font (size 1.27 1.27) (thickness 0.15)) (justify left bottom) hide)
    )
    (property "License" "Apache-2.0" (at 228.6 259.08 0)
      (effects (font (size 1.27 1.27) (thickness 0.15)) (justify left bottom) hide)
    )
    (pin "1")
    (instances
      (project "antmicro-hdmi-mipi-bridge-hw"
        (path ""
          (reference "#PWR0119") (unit 1)
        )
      )
    )
  )

  (symbol (lib_id "antmicropower:GND") (at 382.27 48.26 0) (unit 1)
    (in_bom yes) (on_board yes) (dnp no)
    (property "Reference" "#PWR0113" (at 382.27 54.61 0)
      (effects (font (size 1.27 1.27)) hide)
    )
    (property "Value" "GND" (at 380.365 52.705 0)
      (effects (font (size 1.27 1.27) (thickness 0.15)) (justify left bottom))
    )
    (property "Footprint" "" (at 382.27 48.26 0)
      (effects (font (size 1.27 1.27) (thickness 0.15)) (justify left bottom) hide)
    )
    (property "Datasheet" "" (at 382.27 48.26 0)
      (effects (font (size 1.27 1.27) (thickness 0.15)) (justify left bottom) hide)
    )
    (property "Author" "Antmicro" (at 391.16 55.88 0)
      (effects (font (size 1.27 1.27) (thickness 0.15)) (justify left bottom) hide)
    )
    (property "License" "Apache-2.0" (at 391.16 58.42 0)
      (effects (font (size 1.27 1.27) (thickness 0.15)) (justify left bottom) hide)
    )
    (pin "1")
    (instances
      (project "antmicro-hdmi-mipi-bridge-hw"
        (path ""
          (reference "#PWR0113") (unit 1)
        )
      )
    )
  )

  (symbol (lib_id "antmicropower:GND") (at 219.71 231.14 0) (unit 1)
    (in_bom yes) (on_board yes) (dnp no)
    (property "Reference" "#PWR0117" (at 219.71 237.49 0)
      (effects (font (size 1.27 1.27)) hide)
    )
    (property "Value" "GND" (at 217.805 236.22 0)
      (effects (font (size 1.27 1.27) (thickness 0.15)) (justify left bottom))
    )
    (property "Footprint" "" (at 219.71 231.14 0)
      (effects (font (size 1.27 1.27) (thickness 0.15)) (justify left bottom) hide)
    )
    (property "Datasheet" "" (at 219.71 231.14 0)
      (effects (font (size 1.27 1.27) (thickness 0.15)) (justify left bottom) hide)
    )
    (property "Author" "Antmicro" (at 228.6 238.76 0)
      (effects (font (size 1.27 1.27) (thickness 0.15)) (justify left bottom) hide)
    )
    (property "License" "Apache-2.0" (at 228.6 241.3 0)
      (effects (font (size 1.27 1.27) (thickness 0.15)) (justify left bottom) hide)
    )
    (pin "1")
    (instances
      (project "antmicro-hdmi-mipi-bridge-hw"
        (path ""
          (reference "#PWR0117") (unit 1)
        )
      )
    )
  )

  (symbol (lib_id "antmicropower:GND") (at 364.49 48.26 0) (unit 1)
    (in_bom yes) (on_board yes) (dnp no)
    (property "Reference" "#PWR0112" (at 364.49 54.61 0)
      (effects (font (size 1.27 1.27)) hide)
    )
    (property "Value" "GND" (at 362.585 52.705 0)
      (effects (font (size 1.27 1.27) (thickness 0.15)) (justify left bottom))
    )
    (property "Footprint" "" (at 364.49 48.26 0)
      (effects (font (size 1.27 1.27) (thickness 0.15)) (justify left bottom) hide)
    )
    (property "Datasheet" "" (at 364.49 48.26 0)
      (effects (font (size 1.27 1.27) (thickness 0.15)) (justify left bottom) hide)
    )
    (property "Author" "Antmicro" (at 373.38 55.88 0)
      (effects (font (size 1.27 1.27) (thickness 0.15)) (justify left bottom) hide)
    )
    (property "License" "Apache-2.0" (at 373.38 58.42 0)
      (effects (font (size 1.27 1.27) (thickness 0.15)) (justify left bottom) hide)
    )
    (pin "1")
    (instances
      (project "antmicro-hdmi-mipi-bridge-hw"
        (path ""
          (reference "#PWR0112") (unit 1)
        )
      )
    )
  )

  (symbol (lib_id "antmicroResistors0402:R_2k_0402") (at 152.4 171.45 270) (mirror x) (unit 1)
    (in_bom yes) (on_board yes) (dnp no)
    (property "Reference" "R4" (at 156.845 168.275 90)
      (effects (font (size 1.524 1.524)) (justify right))
    )
    (property "Value" "R_2k_0402" (at 139.7 151.13 0)
      (effects (font (size 1.27 1.27) (thickness 0.15)) (justify left bottom) hide)
    )
    (property "Footprint" "antmicro-footprints:R_0402_1005Metric" (at 137.16 151.13 0)
      (effects (font (size 1.27 1.27) (thickness 0.15)) (justify left bottom) hide)
    )
    (property "Datasheet" "https://www.bourns.com/docs/product-datasheets/cr.pdf" (at 134.62 151.13 0)
      (effects (font (size 1.27 1.27) (thickness 0.15)) (justify left bottom) hide)
    )
    (property "Manufacturer" "Bourns" (at 129.54 151.13 0)
      (effects (font (size 1.27 1.27) (thickness 0.15)) (justify left bottom) hide)
    )
    (property "MPN" "CR0402-FX-2001GLF" (at 132.08 151.13 0)
      (effects (font (size 1.27 1.27) (thickness 0.15)) (justify left bottom) hide)
    )
    (property "Val" "2k" (at 154.305 169.545 90)
      (effects (font (size 1.27 1.27) (thickness 0.15)) (justify left bottom))
    )
    (property "License" "Apache-2.0" (at 127 151.13 0)
      (effects (font (size 1.27 1.27) (thickness 0.15)) (justify left bottom) hide)
    )
    (property "Author" "Antmicro" (at 124.46 151.13 0)
      (effects (font (size 1.27 1.27) (thickness 0.15)) (justify left bottom) hide)
    )
    (property "Tolerance" "1%" (at 142.24 151.13 0)
      (effects (font (size 1.27 1.27)) (justify left bottom) hide)
    )
    (property "Public" "False" (at 121.92 151.13 0)
      (effects (font (size 1.27 1.27)) (justify left bottom) hide)
    )
    (pin "1")
    (pin "2")
    (instances
      (project "antmicro-hdmi-mipi-bridge-hw"
        (path ""
          (reference "R4") (unit 1)
        )
      )
    )
  )

  (symbol (lib_id "antmicroTestPoints:TP_0.75mm_SMD") (at 104.14 185.42 0) (unit 1)
    (in_bom no) (on_board yes) (dnp no) (fields_autoplaced)
    (property "Reference" "TP3" (at 109.22 185.4199 0)
      (effects (font (size 1.27 1.27)) (justify left))
    )
    (property "Value" "TP_0.75mm_SMD" (at 119.38 193.04 0)
      (effects (font (size 1.27 1.27) (thickness 0.15)) (justify left bottom) hide)
    )
    (property "Footprint" "antmicro-footprints:TP_SMD_0.75mm" (at 119.38 195.58 0)
      (effects (font (size 1.27 1.27) (thickness 0.15)) (justify left bottom) hide)
    )
    (property "Datasheet" "" (at 119.38 198.12 0)
      (effects (font (size 1.27 1.27) (thickness 0.15)) (justify left bottom) hide)
    )
    (property "MPN" "" (at 104.14 185.42 0)
      (effects (font (size 1.27 1.27) (thickness 0.15)) (justify left bottom) hide)
    )
    (property "Manufacturer" "" (at 104.14 185.42 0)
      (effects (font (size 1.27 1.27) (thickness 0.15)) (justify left bottom) hide)
    )
    (property "Author" "Antmicro" (at 119.38 200.66 0)
      (effects (font (size 1.27 1.27) (thickness 0.15)) (justify left bottom) hide)
    )
    (property "License" "Apache-2.0" (at 119.38 203.2 0)
      (effects (font (size 1.27 1.27) (thickness 0.15)) (justify left bottom) hide)
    )
    (property "Public" "False" (at 114.3 199.39 0)
      (effects (font (size 1.27 1.27)) (justify left bottom) hide)
    )
    (pin "1")
    (instances
      (project "antmicro-hdmi-mipi-bridge-hw"
        (path ""
          (reference "TP3") (unit 1)
        )
      )
    )
  )

  (symbol (lib_id "antmicropower:+3V3") (at 330.2 168.91 0) (unit 1)
    (in_bom yes) (on_board yes) (dnp no)
    (property "Reference" "#PWR0131" (at 330.2 172.72 0)
      (effects (font (size 1.27 1.27)) hide)
    )
    (property "Value" "+3V3" (at 327.025 165.735 0)
      (effects (font (size 1.27 1.27) (thickness 0.15)) (justify left bottom))
    )
    (property "Footprint" "" (at 330.2 168.91 0)
      (effects (font (size 1.27 1.27) (thickness 0.15)) (justify left bottom) hide)
    )
    (property "Datasheet" "" (at 330.2 168.91 0)
      (effects (font (size 1.27 1.27) (thickness 0.15)) (justify left bottom) hide)
    )
    (property "Author" "Antmicro" (at 345.44 171.45 0)
      (effects (font (size 1.27 1.27) (thickness 0.15)) (justify left bottom) hide)
    )
    (property "License" "Apache-2.0" (at 345.44 173.99 0)
      (effects (font (size 1.27 1.27) (thickness 0.15)) (justify left bottom) hide)
    )
    (pin "1")
    (instances
      (project "antmicro-hdmi-mipi-bridge-hw"
        (path ""
          (reference "#PWR0131") (unit 1)
        )
      )
    )
  )

  (symbol (lib_id "antmicropower:GND") (at 330.2 218.44 0) (unit 1)
    (in_bom yes) (on_board yes) (dnp no)
    (property "Reference" "#PWR0134" (at 330.2 224.79 0)
      (effects (font (size 1.27 1.27)) hide)
    )
    (property "Value" "GND" (at 328.295 222.885 0)
      (effects (font (size 1.27 1.27) (thickness 0.15)) (justify left bottom))
    )
    (property "Footprint" "" (at 330.2 218.44 0)
      (effects (font (size 1.27 1.27) (thickness 0.15)) (justify left bottom) hide)
    )
    (property "Datasheet" "" (at 330.2 218.44 0)
      (effects (font (size 1.27 1.27) (thickness 0.15)) (justify left bottom) hide)
    )
    (property "Author" "Antmicro" (at 339.09 226.06 0)
      (effects (font (size 1.27 1.27) (thickness 0.15)) (justify left bottom) hide)
    )
    (property "License" "Apache-2.0" (at 339.09 228.6 0)
      (effects (font (size 1.27 1.27) (thickness 0.15)) (justify left bottom) hide)
    )
    (pin "1")
    (instances
      (project "antmicro-hdmi-mipi-bridge-hw"
        (path ""
          (reference "#PWR0134") (unit 1)
        )
      )
    )
  )

  (symbol (lib_id "antmicroCapacitors0402:C_470p_0402") (at 219.71 208.28 270) (unit 1)
    (in_bom yes) (on_board yes) (dnp no)
    (property "Reference" "C5" (at 217.17 210.185 90)
      (effects (font (size 1.524 1.524)) (justify right))
    )
    (property "Value" "C_470p_0402" (at 209.55 228.6 0)
      (effects (font (size 1.27 1.27) (thickness 0.15)) (justify left bottom) hide)
    )
    (property "Footprint" "antmicro-footprints:C_0402_1005Metric" (at 207.01 228.6 0)
      (effects (font (size 1.27 1.27) (thickness 0.15)) (justify left bottom) hide)
    )
    (property "Datasheet" "https://www.passivecomponent.com/wp-content/uploads/datasheet/WTC_MLCC_General_Purpose.pdf" (at 204.47 228.6 0)
      (effects (font (size 1.27 1.27) (thickness 0.15)) (justify left bottom) hide)
    )
    (property "Manufacturer" "Walsin" (at 199.39 228.6 0)
      (effects (font (size 1.27 1.27) (thickness 0.15)) (justify left bottom) hide)
    )
    (property "MPN" "0402B471K250CT" (at 201.93 228.6 0)
      (effects (font (size 1.27 1.27) (thickness 0.15)) (justify left bottom) hide)
    )
    (property "Val" "470p" (at 213.995 212.725 90)
      (effects (font (size 1.27 1.27) (thickness 0.15)) (justify left bottom))
    )
    (property "License" "Apache-2.0" (at 196.85 228.6 0)
      (effects (font (size 1.27 1.27) (thickness 0.15)) (justify left bottom) hide)
    )
    (property "Author" "Antmicro" (at 194.31 228.6 0)
      (effects (font (size 1.27 1.27) (thickness 0.15)) (justify left bottom) hide)
    )
    (property "Voltage" "" (at 191.77 228.6 0)
      (effects (font (size 1.27 1.27)) (justify left bottom) hide)
    )
    (property "Dielectric" "" (at 189.23 228.6 0)
      (effects (font (size 1.27 1.27)) (justify left bottom) hide)
    )
    (property "Public" "False" (at 186.69 228.6 0)
      (effects (font (size 1.27 1.27)) (justify left bottom) hide)
    )
    (pin "1")
    (pin "2")
    (instances
      (project "antmicro-hdmi-mipi-bridge-hw"
        (path ""
          (reference "C5") (unit 1)
        )
      )
    )
  )

  (symbol (lib_id "antmicroPMICVoltageRegulatorsLinear:TLV73325PDBVT") (at 331.47 171.45 0) (unit 1)
    (in_bom yes) (on_board yes) (dnp no)
    (property "Reference" "IC1" (at 342.265 165.1 0)
      (effects (font (size 1.27 1.27)))
    )
    (property "Value" "TLV73325PDBVT" (at 334.645 168.275 0)
      (effects (font (size 1.27 1.27) (thickness 0.15)) (justify left bottom) hide)
    )
    (property "Footprint" "antmicro-footprints:SOT-23-5" (at 367.03 179.07 0)
      (effects (font (size 1.27 1.27) (thickness 0.15)) (justify left bottom) hide)
    )
    (property "Datasheet" "https://www.ti.com/lit/ds/symlink/tlv733p.pdf?HQS=dis-mous-null-mousermode-dsf-pf-null-wwe&ts=1676978230940&ref_url=https%253A%252F%252Fwww.mouser.com%252F" (at 367.03 181.61 0)
      (effects (font (size 1.27 1.27) (thickness 0.15)) (justify left bottom) hide)
    )
    (property "MPN" "TLV73325PDBVT" (at 334.01 168.275 0)
      (effects (font (size 1.27 1.27) (thickness 0.15)) (justify left bottom))
    )
    (property "Manufacturer" "Texas Instruments" (at 367.03 186.69 0)
      (effects (font (size 1.27 1.27) (thickness 0.15)) (justify left bottom) hide)
    )
    (property "Author" "Antmicro" (at 367.03 189.23 0)
      (effects (font (size 1.27 1.27) (thickness 0.15)) (justify left bottom) hide)
    )
    (property "License" "Apache-2.0" (at 367.03 191.77 0)
      (effects (font (size 1.27 1.27) (thickness 0.15)) (justify left bottom) hide)
    )
    (pin "1")
    (pin "2")
    (pin "3")
    (pin "4")
    (pin "5")
    (instances
      (project "antmicro-hdmi-mipi-bridge-hw"
        (path ""
          (reference "IC1") (unit 1)
        )
      )
    )
  )

  (symbol (lib_id "antmicroResistors0603:R_0R_0603") (at 228.6 175.26 0) (unit 1)
    (in_bom yes) (on_board yes) (dnp no)
    (property "Reference" "R8" (at 231.14 170.815 0)
      (effects (font (size 1.524 1.524)))
    )
    (property "Value" "R_0R_0603" (at 248.92 187.96 0)
      (effects (font (size 1.27 1.27) (thickness 0.15)) (justify left bottom) hide)
    )
    (property "Footprint" "antmicro-footprints:R_0603_1608Metric" (at 248.92 190.5 0)
      (effects (font (size 1.27 1.27) (thickness 0.15)) (justify left bottom) hide)
    )
    (property "Datasheet" "https://www.bourns.com/docs/product-datasheets/cr.pdf?sfvrsn=574d41f6_14" (at 248.92 193.04 0)
      (effects (font (size 1.27 1.27) (thickness 0.15)) (justify left bottom) hide)
    )
    (property "Manufacturer" "Bourns" (at 248.92 198.12 0)
      (effects (font (size 1.27 1.27) (thickness 0.15)) (justify left bottom) hide)
    )
    (property "MPN" "CR0603-J/-000ELF" (at 248.92 195.58 0)
      (effects (font (size 1.27 1.27) (thickness 0.15)) (justify left bottom) hide)
    )
    (property "Val" "0R" (at 229.87 173.355 0)
      (effects (font (size 1.27 1.27) (thickness 0.15)) (justify left bottom))
    )
    (property "License" "Apache-2.0" (at 248.92 200.66 0)
      (effects (font (size 1.27 1.27) (thickness 0.15)) (justify left bottom) hide)
    )
    (property "Author" "Antmicro" (at 248.92 203.2 0)
      (effects (font (size 1.27 1.27) (thickness 0.15)) (justify left bottom) hide)
    )
    (property "Tolerance" "~" (at 248.92 185.42 0)
      (effects (font (size 1.27 1.27)) (justify left bottom) hide)
    )
    (property "Current" "1A" (at 248.92 205.74 0)
      (effects (font (size 1.27 1.27) (thickness 0.15)) (justify left bottom) hide)
    )
    (property "Public" "False" (at 248.92 205.74 0)
      (effects (font (size 1.27 1.27)) (justify left bottom) hide)
    )
    (pin "1")
    (pin "2")
    (instances
      (project "antmicro-hdmi-mipi-bridge-hw"
        (path ""
          (reference "R8") (unit 1)
        )
      )
    )
  )

  (symbol (lib_id "antmicroFCCConnectors:5051101992") (at 116.84 35.56 0) (unit 1)
    (in_bom no) (on_board no) (dnp yes)
    (property "Reference" "J3" (at 120.65 29.21 0)
      (effects (font (size 1.27 1.27)) (justify left))
    )
    (property "Value" "5051101992" (at 116.205 32.385 0)
      (effects (font (size 1.27 1.27) (thickness 0.15)) (justify left bottom) hide)
    )
    (property "Footprint" "antmicro-footprints:5051101992" (at 139.7 45.72 0)
      (effects (font (size 1.27 1.27) (thickness 0.15)) (justify left bottom) hide)
    )
    (property "Datasheet" "https://www.molex.com/webdocs/datasheets/pdf/en-us/5051101992_FFC_FPC_CONNECTORS.pdf" (at 139.7 48.26 0)
      (effects (font (size 1.27 1.27) (thickness 0.15)) (justify left bottom) hide)
    )
    (property "Manufacturer" "Molex" (at 139.7 50.8 0)
      (effects (font (size 1.27 1.27) (thickness 0.15)) (justify left bottom) hide)
    )
    (property "MPN" "5051101992" (at 115.57 32.385 0)
      (effects (font (size 1.27 1.27) (thickness 0.15)) (justify left bottom))
    )
    (property "Author" "Antmicro" (at 139.7 55.88 0)
      (effects (font (size 1.27 1.27) (thickness 0.15)) (justify left bottom) hide)
    )
    (property "License" "Apache-2.0" (at 139.7 58.42 0)
      (effects (font (size 1.27 1.27) (thickness 0.15)) (justify left bottom) hide)
    )
    (property "DNP" "DNP" (at 0 0 0)
      (effects (font (size 1 1)))
    )
    (pin "1")
    (pin "10")
    (pin "11")
    (pin "12")
    (pin "13")
    (pin "14")
    (pin "15")
    (pin "16")
    (pin "17")
    (pin "18")
    (pin "19")
    (pin "2")
    (pin "3")
    (pin "4")
    (pin "5")
    (pin "6")
    (pin "7")
    (pin "8")
    (pin "9")
    (instances
      (project "antmicro-hdmi-mipi-bridge-hw"
        (path ""
          (reference "J3") (unit 1)
        )
      )
    )
  )

  (symbol (lib_id "antmicroCapacitors0603:C_4u7_0603") (at 231.14 213.36 90) (unit 1)
    (in_bom yes) (on_board yes) (dnp no) (fields_autoplaced)
    (property "Reference" "C9" (at 233.68 209.5436 90)
      (effects (font (size 1.524 1.524)) (justify right))
    )
    (property "Value" "C_4u7_0603" (at 241.3 193.04 0)
      (effects (font (size 1.27 1.27) (thickness 0.15)) (justify left bottom) hide)
    )
    (property "Footprint" "antmicro-footprints:C_0603_1608Metric" (at 243.84 193.04 0)
      (effects (font (size 1.27 1.27) (thickness 0.15)) (justify left bottom) hide)
    )
    (property "Datasheet" "https://product.tdk.com/en/search/capacitor/ceramic/mlcc/info?part_no=C1608X5R1V475M080AC" (at 246.38 193.04 0)
      (effects (font (size 1.27 1.27) (thickness 0.15)) (justify left bottom) hide)
    )
    (property "Manufacturer" "TDK" (at 251.46 193.04 0)
      (effects (font (size 1.27 1.27) (thickness 0.15)) (justify left bottom) hide)
    )
    (property "MPN" "C1608X5R1V475M080AC" (at 248.92 193.04 0)
      (effects (font (size 1.27 1.27) (thickness 0.15)) (justify left bottom) hide)
    )
    (property "Val" "4u7" (at 233.68 212.0836 90)
      (effects (font (size 1.27 1.27) (thickness 0.15)) (justify right))
    )
    (property "License" "Apache-2.0" (at 254 193.04 0)
      (effects (font (size 1.27 1.27) (thickness 0.15)) (justify left bottom) hide)
    )
    (property "Author" "Antmicro" (at 256.54 193.04 0)
      (effects (font (size 1.27 1.27) (thickness 0.15)) (justify left bottom) hide)
    )
    (property "Voltage" "" (at 259.08 193.04 0)
      (effects (font (size 1.27 1.27)) (justify left bottom) hide)
    )
    (property "Dielectric" "" (at 261.62 193.04 0)
      (effects (font (size 1.27 1.27)) (justify left bottom) hide)
    )
    (property "Public" "False" (at 264.16 193.04 0)
      (effects (font (size 1.27 1.27)) (justify left bottom) hide)
    )
    (pin "1")
    (pin "2")
    (instances
      (project "antmicro-hdmi-mipi-bridge-hw"
        (path ""
          (reference "C9") (unit 1)
        )
      )
    )
  )

  (symbol (lib_id "antmicroTestPoints:TP_0.75mm_SMD") (at 355.6 105.41 0) (unit 1)
    (in_bom no) (on_board yes) (dnp no) (fields_autoplaced)
    (property "Reference" "TP4" (at 360.68 105.4099 0)
      (effects (font (size 1.27 1.27)) (justify left))
    )
    (property "Value" "TP_0.75mm_SMD" (at 370.84 113.03 0)
      (effects (font (size 1.27 1.27) (thickness 0.15)) (justify left bottom) hide)
    )
    (property "Footprint" "antmicro-footprints:TP_SMD_0.75mm" (at 370.84 115.57 0)
      (effects (font (size 1.27 1.27) (thickness 0.15)) (justify left bottom) hide)
    )
    (property "Datasheet" "" (at 370.84 118.11 0)
      (effects (font (size 1.27 1.27) (thickness 0.15)) (justify left bottom) hide)
    )
    (property "MPN" "" (at 355.6 105.41 0)
      (effects (font (size 1.27 1.27) (thickness 0.15)) (justify left bottom) hide)
    )
    (property "Manufacturer" "" (at 355.6 105.41 0)
      (effects (font (size 1.27 1.27) (thickness 0.15)) (justify left bottom) hide)
    )
    (property "Author" "Antmicro" (at 370.84 120.65 0)
      (effects (font (size 1.27 1.27) (thickness 0.15)) (justify left bottom) hide)
    )
    (property "License" "Apache-2.0" (at 370.84 123.19 0)
      (effects (font (size 1.27 1.27) (thickness 0.15)) (justify left bottom) hide)
    )
    (property "Public" "False" (at 365.76 119.38 0)
      (effects (font (size 1.27 1.27)) (justify left bottom) hide)
    )
    (pin "1")
    (instances
      (project "antmicro-hdmi-mipi-bridge-hw"
        (path ""
          (reference "TP4") (unit 1)
        )
      )
    )
  )

  (symbol (lib_id "antmicroCapacitors0603:C_10u_0603") (at 330.2 215.9 90) (unit 1)
    (in_bom yes) (on_board yes) (dnp no)
    (property "Reference" "C18" (at 326.39 212.725 90)
      (effects (font (size 1.524 1.524)) (justify left))
    )
    (property "Value" "C_10u_0603" (at 340.36 195.58 0)
      (effects (font (size 1.27 1.27) (thickness 0.15)) (justify left bottom) hide)
    )
    (property "Footprint" "antmicro-footprints:C_0603_1608Metric" (at 342.9 195.58 0)
      (effects (font (size 1.27 1.27) (thickness 0.15)) (justify left bottom) hide)
    )
    (property "Datasheet" "https://www.murata.com/products/productdetail?partno=GRM188R61A106KE69%23" (at 345.44 195.58 0)
      (effects (font (size 1.27 1.27) (thickness 0.15)) (justify left bottom) hide)
    )
    (property "Manufacturer" "Murata" (at 350.52 195.58 0)
      (effects (font (size 1.27 1.27) (thickness 0.15)) (justify left bottom) hide)
    )
    (property "MPN" "GRM188R61A106KE69D" (at 347.98 195.58 0)
      (effects (font (size 1.27 1.27) (thickness 0.15)) (justify left bottom) hide)
    )
    (property "Val" "10u" (at 325.755 213.995 90)
      (effects (font (size 1.27 1.27) (thickness 0.15)) (justify left bottom))
    )
    (property "License" "Apache-2.0" (at 353.06 195.58 0)
      (effects (font (size 1.27 1.27) (thickness 0.15)) (justify left bottom) hide)
    )
    (property "Author" "Antmicro" (at 355.6 195.58 0)
      (effects (font (size 1.27 1.27) (thickness 0.15)) (justify left bottom) hide)
    )
    (property "Voltage" "" (at 358.14 195.58 0)
      (effects (font (size 1.27 1.27)) (justify left bottom) hide)
    )
    (property "Dielectric" "template_dielectric" (at 360.68 195.58 0)
      (effects (font (size 1.27 1.27)) (justify left bottom) hide)
    )
    (property "Public" "False" (at 363.22 195.58 0)
      (effects (font (size 1.27 1.27)) (justify left bottom) hide)
    )
    (pin "1")
    (pin "2")
    (instances
      (project "antmicro-hdmi-mipi-bridge-hw"
        (path ""
          (reference "C18") (unit 1)
        )
      )
    )
  )

  (symbol (lib_id "antmicroInterfaceControllers:TC358743XBG") (at 59.69 157.48 0) (unit 1)
    (in_bom yes) (on_board yes) (dnp no) (fields_autoplaced)
    (property "Reference" "U1" (at 74.93 150.495 0)
      (effects (font (size 1.27 1.27) (thickness 0.15)))
    )
    (property "Value" "TC358743XBG" (at 100.33 149.86 0)
      (effects (font (size 1.27 1.27) (thickness 0.15)) (justify left bottom) hide)
    )
    (property "Footprint" "antmicro-footprints:BGA-64_8x8_6.0x6.0mm" (at 100.33 152.4 0)
      (effects (font (size 1.27 1.27) (thickness 0.15)) (justify left bottom) hide)
    )
    (property "Datasheet" "https://toshiba.semicon-storage.com/info/TC358743XBG_datasheet_en_20171026.pdf?did=35655&prodName=TC358743XBG" (at 100.33 154.94 0)
      (effects (font (size 1.27 1.27) (thickness 0.15)) (justify left bottom) hide)
    )
    (property "MPN" "TC358743XBG" (at 74.93 153.035 0)
      (effects (font (size 1.27 1.27) (thickness 0.15)))
    )
    (property "Manufacturer" "Toshiba" (at 100.33 160.02 0)
      (effects (font (size 1.27 1.27) (thickness 0.15)) (justify left bottom) hide)
    )
    (property "Author" "Antmicro" (at 100.33 162.56 0)
      (effects (font (size 1.27 1.27) (thickness 0.15)) (justify left bottom) hide)
    )
    (property "License" "Apache-2.0" (at 100.33 165.1 0)
      (effects (font (size 1.27 1.27) (thickness 0.15)) (justify left bottom) hide)
    )
    (pin "H6")
    (pin "A8")
    (pin "G2")
    (pin "F5")
    (pin "F7")
    (pin "D2")
    (pin "B5")
    (pin "D1")
    (pin "H7")
    (pin "A3")
    (pin "B7")
    (pin "D7")
    (pin "B1")
    (pin "B6")
    (pin "F4")
    (pin "G8")
    (pin "E5")
    (pin "B2")
    (pin "D4")
    (pin "H8")
    (pin "F6")
    (pin "B3")
    (pin "F1")
    (pin "F3")
    (pin "G6")
    (pin "G4")
    (pin "D5")
    (pin "C5")
    (pin "D3")
    (pin "G1")
    (pin "E4")
    (pin "E2")
    (pin "C3")
    (pin "D8")
    (pin "B8")
    (pin "H3")
    (pin "A1")
    (pin "A5")
    (pin "E7")
    (pin "G5")
    (pin "A7")
    (pin "E6")
    (pin "G3")
    (pin "C8")
    (pin "F2")
    (pin "C6")
    (pin "A2")
    (pin "H2")
    (pin "G7")
    (pin "D6")
    (pin "C1")
    (pin "E8")
    (pin "C7")
    (pin "A6")
    (pin "E1")
    (pin "C2")
    (pin "F8")
    (pin "B4")
    (pin "E3")
    (pin "H5")
    (pin "H4")
    (pin "C4")
    (pin "A4")
    (pin "H1")
    (instances
      (project "antmicro-hdmi-mipi-bridge-hw"
        (path ""
          (reference "U1") (unit 1)
        )
      )
    )
  )

  (symbol (lib_id "antmicroCapacitors0402:C_47p_0402") (at 382.27 45.72 90) (unit 1)
    (in_bom yes) (on_board yes) (dnp no)
    (property "Reference" "C23" (at 388.62 41.275 90)
      (effects (font (size 1.524 1.524)) (justify left))
    )
    (property "Value" "C_47p_0402" (at 392.43 25.4 0)
      (effects (font (size 1.27 1.27) (thickness 0.15)) (justify left bottom) hide)
    )
    (property "Footprint" "antmicro-footprints:C_0402_1005Metric" (at 394.97 25.4 0)
      (effects (font (size 1.27 1.27) (thickness 0.15)) (justify left bottom) hide)
    )
    (property "Datasheet" "https://www.kemet.com/en/us/capacitors/product/C0402C470J5GACTU.html" (at 397.51 25.4 0)
      (effects (font (size 1.27 1.27) (thickness 0.15)) (justify left bottom) hide)
    )
    (property "Manufacturer" "KEMET" (at 402.59 25.4 0)
      (effects (font (size 1.27 1.27) (thickness 0.15)) (justify left bottom) hide)
    )
    (property "MPN" "C0402C470J5GACTU" (at 400.05 25.4 0)
      (effects (font (size 1.27 1.27) (thickness 0.15)) (justify left bottom) hide)
    )
    (property "Val" "47p" (at 388.62 42.545 90)
      (effects (font (size 1.27 1.27) (thickness 0.15)) (justify left bottom))
    )
    (property "License" "Apache-2.0" (at 405.13 25.4 0)
      (effects (font (size 1.27 1.27) (thickness 0.15)) (justify left bottom) hide)
    )
    (property "Author" "Antmicro" (at 407.67 25.4 0)
      (effects (font (size 1.27 1.27) (thickness 0.15)) (justify left bottom) hide)
    )
    (property "Voltage" "" (at 410.21 25.4 0)
      (effects (font (size 1.27 1.27)) (justify left bottom) hide)
    )
    (property "Dielectric" "C0G" (at 412.75 25.4 0)
      (effects (font (size 1.27 1.27)) (justify left bottom) hide)
    )
    (property "Public" "False" (at 415.29 25.4 0)
      (effects (font (size 1.27 1.27)) (justify left bottom) hide)
    )
    (pin "1")
    (pin "2")
    (instances
      (project "antmicro-hdmi-mipi-bridge-hw"
        (path ""
          (reference "C23") (unit 1)
        )
      )
    )
  )

  (symbol (lib_id "antmicroCapacitors0402:C_47p_0402") (at 326.39 45.72 90) (unit 1)
    (in_bom yes) (on_board yes) (dnp no)
    (property "Reference" "C16" (at 332.105 41.275 90)
      (effects (font (size 1.524 1.524)) (justify left))
    )
    (property "Value" "C_47p_0402" (at 336.55 25.4 0)
      (effects (font (size 1.27 1.27) (thickness 0.15)) (justify left bottom) hide)
    )
    (property "Footprint" "antmicro-footprints:C_0402_1005Metric" (at 339.09 25.4 0)
      (effects (font (size 1.27 1.27) (thickness 0.15)) (justify left bottom) hide)
    )
    (property "Datasheet" "https://www.kemet.com/en/us/capacitors/product/C0402C470J5GACTU.html" (at 341.63 25.4 0)
      (effects (font (size 1.27 1.27) (thickness 0.15)) (justify left bottom) hide)
    )
    (property "Manufacturer" "KEMET" (at 346.71 25.4 0)
      (effects (font (size 1.27 1.27) (thickness 0.15)) (justify left bottom) hide)
    )
    (property "MPN" "C0402C470J5GACTU" (at 344.17 25.4 0)
      (effects (font (size 1.27 1.27) (thickness 0.15)) (justify left bottom) hide)
    )
    (property "Val" "47p" (at 332.74 42.545 90)
      (effects (font (size 1.27 1.27) (thickness 0.15)) (justify left bottom))
    )
    (property "License" "Apache-2.0" (at 349.25 25.4 0)
      (effects (font (size 1.27 1.27) (thickness 0.15)) (justify left bottom) hide)
    )
    (property "Author" "Antmicro" (at 351.79 25.4 0)
      (effects (font (size 1.27 1.27) (thickness 0.15)) (justify left bottom) hide)
    )
    (property "Voltage" "" (at 354.33 25.4 0)
      (effects (font (size 1.27 1.27)) (justify left bottom) hide)
    )
    (property "Dielectric" "C0G" (at 356.87 25.4 0)
      (effects (font (size 1.27 1.27)) (justify left bottom) hide)
    )
    (property "Public" "False" (at 359.41 25.4 0)
      (effects (font (size 1.27 1.27)) (justify left bottom) hide)
    )
    (pin "1")
    (pin "2")
    (instances
      (project "antmicro-hdmi-mipi-bridge-hw"
        (path ""
          (reference "C16") (unit 1)
        )
      )
    )
  )

  (symbol (lib_id "antmicropower:GND") (at 231.14 215.9 0) (unit 1)
    (in_bom yes) (on_board yes) (dnp no)
    (property "Reference" "#PWR0105" (at 231.14 222.25 0)
      (effects (font (size 1.27 1.27)) hide)
    )
    (property "Value" "GND" (at 233.045 218.44 0)
      (effects (font (size 1.27 1.27) (thickness 0.15)) (justify left bottom))
    )
    (property "Footprint" "" (at 231.14 215.9 0)
      (effects (font (size 1.27 1.27) (thickness 0.15)) (justify left bottom) hide)
    )
    (property "Datasheet" "" (at 231.14 215.9 0)
      (effects (font (size 1.27 1.27) (thickness 0.15)) (justify left bottom) hide)
    )
    (property "Author" "Antmicro" (at 240.03 223.52 0)
      (effects (font (size 1.27 1.27) (thickness 0.15)) (justify left bottom) hide)
    )
    (property "License" "Apache-2.0" (at 240.03 226.06 0)
      (effects (font (size 1.27 1.27) (thickness 0.15)) (justify left bottom) hide)
    )
    (pin "1")
    (instances
      (project "antmicro-hdmi-mipi-bridge-hw"
        (path ""
          (reference "#PWR0105") (unit 1)
        )
      )
    )
  )

  (symbol (lib_id "antmicroVideoConnectors:HDMI-A_Molex_471511001") (at 48.26 30.48 0) (unit 1)
    (in_bom yes) (on_board yes) (dnp no)
    (property "Reference" "J2" (at 59.69 25.4 0)
      (effects (font (size 1.27 1.27) (thickness 0.15)) (justify left bottom))
    )
    (property "Value" "HDMI-A_Molex_471511001" (at 93.98 35.56 0)
      (effects (font (size 1.27 1.27) (thickness 0.15)) (justify left bottom) hide)
    )
    (property "Footprint" "antmicro-footprints:HDMI-A_Receptacle_Molex_471511001" (at 93.98 38.1 0)
      (effects (font (size 1.27 1.27) (thickness 0.15)) (justify left bottom) hide)
    )
    (property "Datasheet" "https://tools.molex.com/pdm_docs/sd/471511001_sd.pdf" (at 93.98 40.64 0)
      (effects (font (size 1.27 1.27) (thickness 0.15)) (justify left bottom) hide)
    )
    (property "Manufacturer" "Molex" (at 93.98 43.18 0)
      (effects (font (size 1.27 1.27) (thickness 0.15)) (justify left bottom) hide)
    )
    (property "MPN" "471511001" (at 55.245 27.305 0)
      (effects (font (size 1.27 1.27) (thickness 0.15)) (justify left bottom))
    )
    (property "Author" "Antmicro" (at 93.98 48.26 0)
      (effects (font (size 1.27 1.27) (thickness 0.15)) (justify left bottom) hide)
    )
    (property "License" "Apache-2.0" (at 93.98 50.8 0)
      (effects (font (size 1.27 1.27) (thickness 0.15)) (justify left bottom) hide)
    )
    (pin "1")
    (pin "10")
    (pin "11")
    (pin "12")
    (pin "13")
    (pin "14")
    (pin "15")
    (pin "16")
    (pin "17")
    (pin "18")
    (pin "19")
    (pin "2")
    (pin "3")
    (pin "4")
    (pin "5")
    (pin "6")
    (pin "7")
    (pin "8")
    (pin "9")
    (pin "SH")
    (instances
      (project "antmicro-hdmi-mipi-bridge-hw"
        (path ""
          (reference "J2") (unit 1)
        )
      )
    )
  )

  (symbol (lib_id "antmicropower:GND") (at 381 93.98 0) (unit 1)
    (in_bom yes) (on_board yes) (dnp no)
    (property "Reference" "#PWR0116" (at 381 100.33 0)
      (effects (font (size 1.27 1.27)) hide)
    )
    (property "Value" "GND" (at 384.81 95.25 0)
      (effects (font (size 1.27 1.27) (thickness 0.15)) (justify left bottom))
    )
    (property "Footprint" "" (at 381 93.98 0)
      (effects (font (size 1.27 1.27) (thickness 0.15)) (justify left bottom) hide)
    )
    (property "Datasheet" "" (at 381 93.98 0)
      (effects (font (size 1.27 1.27) (thickness 0.15)) (justify left bottom) hide)
    )
    (property "Author" "Antmicro" (at 389.89 101.6 0)
      (effects (font (size 1.27 1.27) (thickness 0.15)) (justify left bottom) hide)
    )
    (property "License" "Apache-2.0" (at 389.89 104.14 0)
      (effects (font (size 1.27 1.27) (thickness 0.15)) (justify left bottom) hide)
    )
    (pin "1")
    (instances
      (project "antmicro-hdmi-mipi-bridge-hw"
        (path ""
          (reference "#PWR0116") (unit 1)
        )
      )
    )
  )

  (symbol (lib_id "antmicropower:GND") (at 104.14 261.62 0) (unit 1)
    (in_bom yes) (on_board yes) (dnp no)
    (property "Reference" "#PWR0138" (at 104.14 267.97 0)
      (effects (font (size 1.27 1.27)) hide)
    )
    (property "Value" "GND" (at 102.235 266.7 0)
      (effects (font (size 1.27 1.27) (thickness 0.15)) (justify left bottom))
    )
    (property "Footprint" "" (at 104.14 261.62 0)
      (effects (font (size 1.27 1.27) (thickness 0.15)) (justify left bottom) hide)
    )
    (property "Datasheet" "" (at 104.14 261.62 0)
      (effects (font (size 1.27 1.27) (thickness 0.15)) (justify left bottom) hide)
    )
    (property "Author" "Antmicro" (at 113.03 269.24 0)
      (effects (font (size 1.27 1.27) (thickness 0.15)) (justify left bottom) hide)
    )
    (property "License" "Apache-2.0" (at 113.03 271.78 0)
      (effects (font (size 1.27 1.27) (thickness 0.15)) (justify left bottom) hide)
    )
    (pin "1")
    (instances
      (project "antmicro-hdmi-mipi-bridge-hw"
        (path ""
          (reference "#PWR0138") (unit 1)
        )
      )
    )
  )

  (symbol (lib_id "antmicropower:+3V3") (at 146.05 162.56 0) (unit 1)
    (in_bom yes) (on_board yes) (dnp no)
    (property "Reference" "#PWR0135" (at 146.05 166.37 0)
      (effects (font (size 1.27 1.27)) hide)
    )
    (property "Value" "+3V3" (at 142.875 159.385 0)
      (effects (font (size 1.27 1.27) (thickness 0.15)) (justify left bottom))
    )
    (property "Footprint" "" (at 146.05 162.56 0)
      (effects (font (size 1.27 1.27) (thickness 0.15)) (justify left bottom) hide)
    )
    (property "Datasheet" "" (at 146.05 162.56 0)
      (effects (font (size 1.27 1.27) (thickness 0.15)) (justify left bottom) hide)
    )
    (property "Author" "Antmicro" (at 161.29 165.1 0)
      (effects (font (size 1.27 1.27) (thickness 0.15)) (justify left bottom) hide)
    )
    (property "License" "Apache-2.0" (at 161.29 167.64 0)
      (effects (font (size 1.27 1.27) (thickness 0.15)) (justify left bottom) hide)
    )
    (pin "1")
    (instances
      (project "antmicro-hdmi-mipi-bridge-hw"
        (path ""
          (reference "#PWR0135") (unit 1)
        )
      )
    )
  )

  (symbol (lib_id "antmicropower:GND") (at 76.2 90.17 0) (unit 1)
    (in_bom yes) (on_board yes) (dnp no)
    (property "Reference" "#PWR0141" (at 76.2 96.52 0)
      (effects (font (size 1.27 1.27)) hide)
    )
    (property "Value" "GND" (at 74.295 94.615 0)
      (effects (font (size 1.27 1.27) (thickness 0.15)) (justify left bottom))
    )
    (property "Footprint" "" (at 76.2 90.17 0)
      (effects (font (size 1.27 1.27) (thickness 0.15)) (justify left bottom) hide)
    )
    (property "Datasheet" "" (at 76.2 90.17 0)
      (effects (font (size 1.27 1.27) (thickness 0.15)) (justify left bottom) hide)
    )
    (property "Author" "Antmicro" (at 85.09 97.79 0)
      (effects (font (size 1.27 1.27) (thickness 0.15)) (justify left bottom) hide)
    )
    (property "License" "Apache-2.0" (at 85.09 100.33 0)
      (effects (font (size 1.27 1.27) (thickness 0.15)) (justify left bottom) hide)
    )
    (pin "1")
    (instances
      (project "antmicro-hdmi-mipi-bridge-hw"
        (path ""
          (reference "#PWR0141") (unit 1)
        )
      )
    )
  )

  (symbol (lib_id "antmicropower:GND") (at 89.535 80.01 0) (mirror y) (unit 1)
    (in_bom yes) (on_board yes) (dnp no)
    (property "Reference" "#PWR0142" (at 89.535 86.36 0)
      (effects (font (size 1.27 1.27)) hide)
    )
    (property "Value" "GND" (at 91.44 84.455 0)
      (effects (font (size 1.27 1.27) (thickness 0.15)) (justify left bottom))
    )
    (property "Footprint" "" (at 89.535 80.01 0)
      (effects (font (size 1.27 1.27) (thickness 0.15)) (justify left bottom) hide)
    )
    (property "Datasheet" "" (at 89.535 80.01 0)
      (effects (font (size 1.27 1.27) (thickness 0.15)) (justify left bottom) hide)
    )
    (property "Author" "Antmicro" (at 80.645 87.63 0)
      (effects (font (size 1.27 1.27) (thickness 0.15)) (justify left bottom) hide)
    )
    (property "License" "Apache-2.0" (at 80.645 90.17 0)
      (effects (font (size 1.27 1.27) (thickness 0.15)) (justify left bottom) hide)
    )
    (pin "1")
    (instances
      (project "antmicro-hdmi-mipi-bridge-hw"
        (path ""
          (reference "#PWR0142") (unit 1)
        )
      )
    )
  )

  (symbol (lib_id "antmicroTestPoints:TP_0.75mm_SMD") (at 92.71 203.2 0) (unit 1)
    (in_bom no) (on_board yes) (dnp no) (fields_autoplaced)
    (property "Reference" "TP2" (at 97.79 203.1999 0)
      (effects (font (size 1.27 1.27)) (justify left))
    )
    (property "Value" "TP_0.75mm_SMD" (at 107.95 210.82 0)
      (effects (font (size 1.27 1.27) (thickness 0.15)) (justify left bottom) hide)
    )
    (property "Footprint" "antmicro-footprints:TP_SMD_0.75mm" (at 107.95 213.36 0)
      (effects (font (size 1.27 1.27) (thickness 0.15)) (justify left bottom) hide)
    )
    (property "Datasheet" "" (at 107.95 215.9 0)
      (effects (font (size 1.27 1.27) (thickness 0.15)) (justify left bottom) hide)
    )
    (property "MPN" "" (at 92.71 203.2 0)
      (effects (font (size 1.27 1.27) (thickness 0.15)) (justify left bottom) hide)
    )
    (property "Manufacturer" "" (at 92.71 203.2 0)
      (effects (font (size 1.27 1.27) (thickness 0.15)) (justify left bottom) hide)
    )
    (property "Author" "Antmicro" (at 107.95 218.44 0)
      (effects (font (size 1.27 1.27) (thickness 0.15)) (justify left bottom) hide)
    )
    (property "License" "Apache-2.0" (at 107.95 220.98 0)
      (effects (font (size 1.27 1.27) (thickness 0.15)) (justify left bottom) hide)
    )
    (property "Public" "False" (at 102.87 217.17 0)
      (effects (font (size 1.27 1.27)) (justify left bottom) hide)
    )
    (pin "1")
    (instances
      (project "antmicro-hdmi-mipi-bridge-hw"
        (path ""
          (reference "TP2") (unit 1)
        )
      )
    )
  )
)
